FILE_TYPE = MACRO_DRAWING;
SET COLOR_WIRE YELLOW;
SET COLOR_PROP ORANGE;
SET COLOR_DOT WHITE;
SET COLOR_ARC YELLOW;
SET COLOR_BODY GREEN;
SET COLOR_NOTE PURPLE;
SET PROP_DISPLAY VALUE;
SET PAGE_NUMBER P22;
FORCEADD GENOA_SP5..11
(-4775 4925);
FORCEPROP 1 LAST LOCATION U25
J 0
(-5870 6181);
DISPLAY 0.489362 (-5870 6181);
PAINT SKYBLUE (-5870 6181);
FORCEPROP 0 LAST $SEC 11
J 0
(-5850 6225);
DISPLAY 0.680851 (-5850 6225);
PAINT MONO (-5850 6225);
DISPLAY INVISIBLE (-5850 6225);
FORCEPROP 0 LAST CDS_SEC 11
J 0
(-5875 6175);
DISPLAY 1.021277 (-5875 6175);
DISPLAY INVISIBLE (-5875 6175);
FORCEPROP 0 LASTPIN (-6025 5625) $PN M40
J 2
(-6035 5635);
DISPLAY 0.489362 (-6035 5635);
PAINT MONO (-6035 5635);
FORCEPROP 0 LASTPIN (-6025 5525) $PN K40
J 2
(-6035 5535);
DISPLAY 0.489362 (-6035 5535);
PAINT MONO (-6035 5535);
FORCEPROP 0 LASTPIN (-6025 5425) $PN H40
J 2
(-6035 5435);
DISPLAY 0.489362 (-6035 5435);
PAINT MONO (-6035 5435);
FORCEPROP 0 LASTPIN (-6025 5325) $PN L43
J 2
(-6035 5335);
DISPLAY 0.489362 (-6035 5335);
PAINT MONO (-6035 5335);
FORCEPROP 0 LASTPIN (-6025 5225) $PN G43
J 2
(-6035 5235);
DISPLAY 0.489362 (-6035 5235);
PAINT MONO (-6035 5235);
FORCEPROP 0 LASTPIN (-6025 5125) $PN J43
J 2
(-6035 5135);
DISPLAY 0.489362 (-6035 5135);
PAINT MONO (-6035 5135);
FORCEPROP 0 LASTPIN (-6025 5025) $PN L46
J 2
(-6035 5035);
DISPLAY 0.489362 (-6035 5035);
PAINT MONO (-6035 5035);
FORCEPROP 0 LASTPIN (-6025 4925) $PN G46
J 2
(-6035 4935);
DISPLAY 0.489362 (-6035 4935);
PAINT MONO (-6035 4935);
FORCEPROP 0 LASTPIN (-6025 4825) $PN J46
J 2
(-6035 4835);
DISPLAY 0.489362 (-6035 4835);
PAINT MONO (-6035 4835);
FORCEPROP 0 LASTPIN (-6025 4725) $PN L49
J 2
(-6035 4735);
DISPLAY 0.489362 (-6035 4735);
PAINT MONO (-6035 4735);
FORCEPROP 0 LASTPIN (-6025 4625) $PN G49
J 2
(-6035 4635);
DISPLAY 0.489362 (-6035 4635);
PAINT MONO (-6035 4635);
FORCEPROP 0 LASTPIN (-6025 4525) $PN J49
J 2
(-6035 4535);
DISPLAY 0.489362 (-6035 4535);
PAINT MONO (-6035 4535);
FORCEPROP 0 LASTPIN (-6025 4425) $PN L52
J 2
(-6035 4435);
DISPLAY 0.489362 (-6035 4435);
PAINT MONO (-6035 4435);
FORCEPROP 0 LASTPIN (-6025 4325) $PN G52
J 2
(-6035 4335);
DISPLAY 0.489362 (-6035 4335);
PAINT MONO (-6035 4335);
FORCEPROP 0 LASTPIN (-6025 4225) $PN J52
J 2
(-6035 4235);
DISPLAY 0.489362 (-6035 4235);
PAINT MONO (-6035 4235);
FORCEPROP 0 LASTPIN (-6025 4125) $PN N52
J 2
(-6035 4135);
DISPLAY 0.489362 (-6035 4135);
PAINT MONO (-6035 4135);
FORCEPROP 0 LASTPIN (-6025 5675) $PN M41
J 2
(-6035 5685);
DISPLAY 0.489362 (-6035 5685);
PAINT MONO (-6035 5685);
FORCEPROP 0 LASTPIN (-6025 5575) $PN K41
J 2
(-6035 5585);
DISPLAY 0.489362 (-6035 5585);
PAINT MONO (-6035 5585);
FORCEPROP 0 LASTPIN (-6025 5475) $PN H41
J 2
(-6035 5485);
DISPLAY 0.489362 (-6035 5485);
PAINT MONO (-6035 5485);
FORCEPROP 0 LASTPIN (-6025 5375) $PN L44
J 2
(-6035 5385);
DISPLAY 0.489362 (-6035 5385);
PAINT MONO (-6035 5385);
FORCEPROP 0 LASTPIN (-6025 5275) $PN G44
J 2
(-6035 5285);
DISPLAY 0.489362 (-6035 5285);
PAINT MONO (-6035 5285);
FORCEPROP 0 LASTPIN (-6025 5175) $PN J44
J 2
(-6035 5185);
DISPLAY 0.489362 (-6035 5185);
PAINT MONO (-6035 5185);
FORCEPROP 0 LASTPIN (-6025 5075) $PN L47
J 2
(-6035 5085);
DISPLAY 0.489362 (-6035 5085);
PAINT MONO (-6035 5085);
FORCEPROP 0 LASTPIN (-6025 4975) $PN G47
J 2
(-6035 4985);
DISPLAY 0.489362 (-6035 4985);
PAINT MONO (-6035 4985);
FORCEPROP 0 LASTPIN (-6025 4875) $PN J47
J 2
(-6035 4885);
DISPLAY 0.489362 (-6035 4885);
PAINT MONO (-6035 4885);
FORCEPROP 0 LASTPIN (-6025 4775) $PN L50
J 2
(-6035 4785);
DISPLAY 0.489362 (-6035 4785);
PAINT MONO (-6035 4785);
FORCEPROP 0 LASTPIN (-6025 4675) $PN G50
J 2
(-6035 4685);
DISPLAY 0.489362 (-6035 4685);
PAINT MONO (-6035 4685);
FORCEPROP 0 LASTPIN (-6025 4575) $PN J50
J 2
(-6035 4585);
DISPLAY 0.489362 (-6035 4585);
PAINT MONO (-6035 4585);
FORCEPROP 0 LASTPIN (-6025 4475) $PN L53
J 2
(-6035 4485);
DISPLAY 0.489362 (-6035 4485);
PAINT MONO (-6035 4485);
FORCEPROP 0 LASTPIN (-6025 4375) $PN G53
J 2
(-6035 4385);
DISPLAY 0.489362 (-6035 4385);
PAINT MONO (-6035 4385);
FORCEPROP 0 LASTPIN (-6025 4275) $PN J53
J 2
(-6035 4285);
DISPLAY 0.489362 (-6035 4285);
PAINT MONO (-6035 4285);
FORCEPROP 0 LASTPIN (-6025 4175) $PN N53
J 2
(-6035 4185);
DISPLAY 0.489362 (-6035 4185);
PAINT MONO (-6035 4185);
FORCEPROP 0 LASTPIN (-3525 5625) $PN AF41
J 0
(-3515 5635);
DISPLAY 0.489362 (-3515 5635);
PAINT MONO (-3515 5635);
FORCEPROP 0 LASTPIN (-3525 5525) $PN AD41
J 0
(-3515 5535);
DISPLAY 0.489362 (-3515 5535);
PAINT MONO (-3515 5535);
FORCEPROP 0 LASTPIN (-3525 5425) $PN AB41
J 0
(-3515 5435);
DISPLAY 0.489362 (-3515 5435);
PAINT MONO (-3515 5435);
FORCEPROP 0 LASTPIN (-3525 5325) $PN AG44
J 0
(-3515 5335);
DISPLAY 0.489362 (-3515 5335);
PAINT MONO (-3515 5335);
FORCEPROP 0 LASTPIN (-3525 5225) $PN AA44
J 0
(-3515 5235);
DISPLAY 0.489362 (-3515 5235);
PAINT MONO (-3515 5235);
FORCEPROP 0 LASTPIN (-3525 5125) $PN AC44
J 0
(-3515 5135);
DISPLAY 0.489362 (-3515 5135);
PAINT MONO (-3515 5135);
FORCEPROP 0 LASTPIN (-3525 5025) $PN AE44
J 0
(-3515 5035);
DISPLAY 0.489362 (-3515 5035);
PAINT MONO (-3515 5035);
FORCEPROP 0 LASTPIN (-3525 4925) $PN AG47
J 0
(-3515 4935);
DISPLAY 0.489362 (-3515 4935);
PAINT MONO (-3515 4935);
FORCEPROP 0 LASTPIN (-3525 4825) $PN AC47
J 0
(-3515 4835);
DISPLAY 0.489362 (-3515 4835);
PAINT MONO (-3515 4835);
FORCEPROP 0 LASTPIN (-3525 4725) $PN AE47
J 0
(-3515 4735);
DISPLAY 0.489362 (-3515 4735);
PAINT MONO (-3515 4735);
FORCEPROP 0 LASTPIN (-3525 4625) $PN AG50
J 0
(-3515 4635);
DISPLAY 0.489362 (-3515 4635);
PAINT MONO (-3515 4635);
FORCEPROP 0 LASTPIN (-3525 4525) $PN AC50
J 0
(-3515 4535);
DISPLAY 0.489362 (-3515 4535);
PAINT MONO (-3515 4535);
FORCEPROP 0 LASTPIN (-3525 4425) $PN AE50
J 0
(-3515 4435);
DISPLAY 0.489362 (-3515 4435);
PAINT MONO (-3515 4435);
FORCEPROP 0 LASTPIN (-3525 4325) $PN AG53
J 0
(-3515 4335);
DISPLAY 0.489362 (-3515 4335);
PAINT MONO (-3515 4335);
FORCEPROP 0 LASTPIN (-3525 4225) $PN AC53
J 0
(-3515 4235);
DISPLAY 0.489362 (-3515 4235);
PAINT MONO (-3515 4235);
FORCEPROP 0 LASTPIN (-3525 4125) $PN AE53
J 0
(-3515 4135);
DISPLAY 0.489362 (-3515 4135);
PAINT MONO (-3515 4135);
FORCEPROP 0 LASTPIN (-3525 5675) $PN AF40
J 0
(-3515 5685);
DISPLAY 0.489362 (-3515 5685);
PAINT MONO (-3515 5685);
FORCEPROP 0 LASTPIN (-3525 5575) $PN AD40
J 0
(-3515 5585);
DISPLAY 0.489362 (-3515 5585);
PAINT MONO (-3515 5585);
FORCEPROP 0 LASTPIN (-3525 5475) $PN AB40
J 0
(-3515 5485);
DISPLAY 0.489362 (-3515 5485);
PAINT MONO (-3515 5485);
FORCEPROP 0 LASTPIN (-3525 5375) $PN AG43
J 0
(-3515 5385);
DISPLAY 0.489362 (-3515 5385);
PAINT MONO (-3515 5385);
FORCEPROP 0 LASTPIN (-3525 5275) $PN AA43
J 0
(-3515 5285);
DISPLAY 0.489362 (-3515 5285);
PAINT MONO (-3515 5285);
FORCEPROP 0 LASTPIN (-3525 5175) $PN AC43
J 0
(-3515 5185);
DISPLAY 0.489362 (-3515 5185);
PAINT MONO (-3515 5185);
FORCEPROP 0 LASTPIN (-3525 5075) $PN AE43
J 0
(-3515 5085);
DISPLAY 0.489362 (-3515 5085);
PAINT MONO (-3515 5085);
FORCEPROP 0 LASTPIN (-3525 4975) $PN AG46
J 0
(-3515 4985);
DISPLAY 0.489362 (-3515 4985);
PAINT MONO (-3515 4985);
FORCEPROP 0 LASTPIN (-3525 4875) $PN AC46
J 0
(-3515 4885);
DISPLAY 0.489362 (-3515 4885);
PAINT MONO (-3515 4885);
FORCEPROP 0 LASTPIN (-3525 4775) $PN AE46
J 0
(-3515 4785);
DISPLAY 0.489362 (-3515 4785);
PAINT MONO (-3515 4785);
FORCEPROP 0 LASTPIN (-3525 4675) $PN AG49
J 0
(-3515 4685);
DISPLAY 0.489362 (-3515 4685);
PAINT MONO (-3515 4685);
FORCEPROP 0 LASTPIN (-3525 4575) $PN AC49
J 0
(-3515 4585);
DISPLAY 0.489362 (-3515 4585);
PAINT MONO (-3515 4585);
FORCEPROP 0 LASTPIN (-3525 4475) $PN AE49
J 0
(-3515 4485);
DISPLAY 0.489362 (-3515 4485);
PAINT MONO (-3515 4485);
FORCEPROP 0 LASTPIN (-3525 4375) $PN AG52
J 0
(-3515 4385);
DISPLAY 0.489362 (-3515 4385);
PAINT MONO (-3515 4385);
FORCEPROP 0 LASTPIN (-3525 4275) $PN AC52
J 0
(-3515 4285);
DISPLAY 0.489362 (-3515 4285);
PAINT MONO (-3515 4285);
FORCEPROP 0 LASTPIN (-3525 4175) $PN AE52
J 0
(-3515 4185);
DISPLAY 0.489362 (-3515 4185);
PAINT MONO (-3515 4185);
FORCEPROP 2 LAST PART_TYPE SMLF
J 0
(-5875 6103);
DISPLAY 1.021277 (-5875 6103);
FORCEPROP 1 LAST MATERIAL IO
J 0
(-5870 5907);
DISPLAY 0.489362 (-5870 5907);
PAINT SKYBLUE (-5870 5907);
FORCEPROP 2 LAST VALUE SOCKET6096_13568-001
J 0
(-5875 6003);
DISPLAY 0.489362 (-5875 6003);
PAINT SKYBLUE (-5875 6003);
FORCEPROP 2 LAST CDS_LIB pure_quanta
J 0
(-4775 4925);
DISPLAY INVISIBLE (-4775 4925);
FORCEPROP 1 LAST NEEDS_NO_SIZE TRUE
J 0
(-4775 4925);
DISPLAY 0.723404 (-4775 4925);
PAINT GREEN (-4775 4925);
DISPLAY INVISIBLE (-4775 4925);
FORCEPROP 1 LAST CDS_LMAN_SYM_OUTLINE -1100,950,1100,-950
J 0
(-4775 4925);
DISPLAY 0.468085 (-4775 4925);
PAINT GREEN (-4775 4925);
DISPLAY INVISIBLE (-4775 4925);
FORCEPROP 1 LAST PATH I207
J 0
(-4775 4925);
DISPLAY 0.723404 (-4775 4925);
PAINT GREEN (-4775 4925);
DISPLAY INVISIBLE (-4775 4925);
FORCEPROP 1 LAST PART_NUMBER DGA^6000030
J 0
(-5870 6034);
DISPLAY 0.489362 (-5870 6034);
PAINT SKYBLUE (-5870 6034);
DISPLAY INVISIBLE (-5870 6034);
FORCEADD GENOA_SP5..12
(-4775 2200);
FORCEPROP 1 LAST LOCATION U25
J 0
(-5870 3456);
DISPLAY 0.489362 (-5870 3456);
PAINT SKYBLUE (-5870 3456);
FORCEPROP 0 LAST $SEC 12
J 0
(-5850 3500);
DISPLAY 0.680851 (-5850 3500);
PAINT MONO (-5850 3500);
DISPLAY INVISIBLE (-5850 3500);
FORCEPROP 0 LAST CDS_SEC 12
J 0
(-5875 3400);
DISPLAY 1.021277 (-5875 3400);
DISPLAY INVISIBLE (-5875 3400);
FORCEPROP 0 LASTPIN (-6025 2900) $PN V40
J 2
(-6035 2910);
DISPLAY 0.489362 (-6035 2910);
PAINT MONO (-6035 2910);
FORCEPROP 0 LASTPIN (-6025 2800) $PN T40
J 2
(-6035 2810);
DISPLAY 0.489362 (-6035 2810);
PAINT MONO (-6035 2810);
FORCEPROP 0 LASTPIN (-6025 2700) $PN P40
J 2
(-6035 2710);
DISPLAY 0.489362 (-6035 2710);
PAINT MONO (-6035 2710);
FORCEPROP 0 LASTPIN (-6025 2600) $PN U43
J 2
(-6035 2610);
DISPLAY 0.489362 (-6035 2610);
PAINT MONO (-6035 2610);
FORCEPROP 0 LASTPIN (-6025 2500) $PN N43
J 2
(-6035 2510);
DISPLAY 0.489362 (-6035 2510);
PAINT MONO (-6035 2510);
FORCEPROP 0 LASTPIN (-6025 2400) $PN R43
J 2
(-6035 2410);
DISPLAY 0.489362 (-6035 2410);
PAINT MONO (-6035 2410);
FORCEPROP 0 LASTPIN (-6025 2300) $PN U46
J 2
(-6035 2310);
DISPLAY 0.489362 (-6035 2310);
PAINT MONO (-6035 2310);
FORCEPROP 0 LASTPIN (-6025 2200) $PN N46
J 2
(-6035 2210);
DISPLAY 0.489362 (-6035 2210);
PAINT MONO (-6035 2210);
FORCEPROP 0 LASTPIN (-6025 2100) $PN R46
J 2
(-6035 2110);
DISPLAY 0.489362 (-6035 2110);
PAINT MONO (-6035 2110);
FORCEPROP 0 LASTPIN (-6025 2000) $PN W49
J 2
(-6035 2010);
DISPLAY 0.489362 (-6035 2010);
PAINT MONO (-6035 2010);
FORCEPROP 0 LASTPIN (-6025 1900) $PN N49
J 2
(-6035 1910);
DISPLAY 0.489362 (-6035 1910);
PAINT MONO (-6035 1910);
FORCEPROP 0 LASTPIN (-6025 1800) $PN R49
J 2
(-6035 1810);
DISPLAY 0.489362 (-6035 1810);
PAINT MONO (-6035 1810);
FORCEPROP 0 LASTPIN (-6025 1700) $PN U49
J 2
(-6035 1710);
DISPLAY 0.489362 (-6035 1710);
PAINT MONO (-6035 1710);
FORCEPROP 0 LASTPIN (-6025 1600) $PN W52
J 2
(-6035 1610);
DISPLAY 0.489362 (-6035 1610);
PAINT MONO (-6035 1610);
FORCEPROP 0 LASTPIN (-6025 1500) $PN R52
J 2
(-6035 1510);
DISPLAY 0.489362 (-6035 1510);
PAINT MONO (-6035 1510);
FORCEPROP 0 LASTPIN (-6025 1400) $PN U52
J 2
(-6035 1410);
DISPLAY 0.489362 (-6035 1410);
PAINT MONO (-6035 1410);
FORCEPROP 0 LASTPIN (-6025 2950) $PN V41
J 2
(-6035 2960);
DISPLAY 0.489362 (-6035 2960);
PAINT MONO (-6035 2960);
FORCEPROP 0 LASTPIN (-6025 2850) $PN T41
J 2
(-6035 2860);
DISPLAY 0.489362 (-6035 2860);
PAINT MONO (-6035 2860);
FORCEPROP 0 LASTPIN (-6025 2750) $PN P41
J 2
(-6035 2760);
DISPLAY 0.489362 (-6035 2760);
PAINT MONO (-6035 2760);
FORCEPROP 0 LASTPIN (-6025 2650) $PN U44
J 2
(-6035 2660);
DISPLAY 0.489362 (-6035 2660);
PAINT MONO (-6035 2660);
FORCEPROP 0 LASTPIN (-6025 2550) $PN N44
J 2
(-6035 2560);
DISPLAY 0.489362 (-6035 2560);
PAINT MONO (-6035 2560);
FORCEPROP 0 LASTPIN (-6025 2450) $PN R44
J 2
(-6035 2460);
DISPLAY 0.489362 (-6035 2460);
PAINT MONO (-6035 2460);
FORCEPROP 0 LASTPIN (-6025 2350) $PN U47
J 2
(-6035 2360);
DISPLAY 0.489362 (-6035 2360);
PAINT MONO (-6035 2360);
FORCEPROP 0 LASTPIN (-6025 2250) $PN N47
J 2
(-6035 2260);
DISPLAY 0.489362 (-6035 2260);
PAINT MONO (-6035 2260);
FORCEPROP 0 LASTPIN (-6025 2150) $PN R47
J 2
(-6035 2160);
DISPLAY 0.489362 (-6035 2160);
PAINT MONO (-6035 2160);
FORCEPROP 0 LASTPIN (-6025 2050) $PN W50
J 2
(-6035 2060);
DISPLAY 0.489362 (-6035 2060);
PAINT MONO (-6035 2060);
FORCEPROP 0 LASTPIN (-6025 1950) $PN N50
J 2
(-6035 1960);
DISPLAY 0.489362 (-6035 1960);
PAINT MONO (-6035 1960);
FORCEPROP 0 LASTPIN (-6025 1850) $PN R50
J 2
(-6035 1860);
DISPLAY 0.489362 (-6035 1860);
PAINT MONO (-6035 1860);
FORCEPROP 0 LASTPIN (-6025 1750) $PN U50
J 2
(-6035 1760);
DISPLAY 0.489362 (-6035 1760);
PAINT MONO (-6035 1760);
FORCEPROP 0 LASTPIN (-6025 1650) $PN W53
J 2
(-6035 1660);
DISPLAY 0.489362 (-6035 1660);
PAINT MONO (-6035 1660);
FORCEPROP 0 LASTPIN (-6025 1550) $PN R53
J 2
(-6035 1560);
DISPLAY 0.489362 (-6035 1560);
PAINT MONO (-6035 1560);
FORCEPROP 0 LASTPIN (-6025 1450) $PN U53
J 2
(-6035 1460);
DISPLAY 0.489362 (-6035 1460);
PAINT MONO (-6035 1460);
FORCEPROP 0 LASTPIN (-3525 2900) $PN AP41
J 0
(-3515 2910);
DISPLAY 0.489362 (-3515 2910);
PAINT MONO (-3515 2910);
FORCEPROP 0 LASTPIN (-3525 2800) $PN AM41
J 0
(-3515 2810);
DISPLAY 0.489362 (-3515 2810);
PAINT MONO (-3515 2810);
FORCEPROP 0 LASTPIN (-3525 2700) $PN AH41
J 0
(-3515 2710);
DISPLAY 0.489362 (-3515 2710);
PAINT MONO (-3515 2710);
FORCEPROP 0 LASTPIN (-3525 2600) $PN AK41
J 0
(-3515 2610);
DISPLAY 0.489362 (-3515 2610);
PAINT MONO (-3515 2610);
FORCEPROP 0 LASTPIN (-3525 2500) $PN AN44
J 0
(-3515 2510);
DISPLAY 0.489362 (-3515 2510);
PAINT MONO (-3515 2510);
FORCEPROP 0 LASTPIN (-3525 2400) $PN AJ44
J 0
(-3515 2410);
DISPLAY 0.489362 (-3515 2410);
PAINT MONO (-3515 2410);
FORCEPROP 0 LASTPIN (-3525 2300) $PN AL44
J 0
(-3515 2310);
DISPLAY 0.489362 (-3515 2310);
PAINT MONO (-3515 2310);
FORCEPROP 0 LASTPIN (-3525 2200) $PN AN47
J 0
(-3515 2210);
DISPLAY 0.489362 (-3515 2210);
PAINT MONO (-3515 2210);
FORCEPROP 0 LASTPIN (-3525 2100) $PN AJ47
J 0
(-3515 2110);
DISPLAY 0.489362 (-3515 2110);
PAINT MONO (-3515 2110);
FORCEPROP 0 LASTPIN (-3525 2000) $PN AL47
J 0
(-3515 2010);
DISPLAY 0.489362 (-3515 2010);
PAINT MONO (-3515 2010);
FORCEPROP 0 LASTPIN (-3525 1900) $PN AN50
J 0
(-3515 1910);
DISPLAY 0.489362 (-3515 1910);
PAINT MONO (-3515 1910);
FORCEPROP 0 LASTPIN (-3525 1800) $PN AJ50
J 0
(-3515 1810);
DISPLAY 0.489362 (-3515 1810);
PAINT MONO (-3515 1810);
FORCEPROP 0 LASTPIN (-3525 1700) $PN AL50
J 0
(-3515 1710);
DISPLAY 0.489362 (-3515 1710);
PAINT MONO (-3515 1710);
FORCEPROP 0 LASTPIN (-3525 1600) $PN AN53
J 0
(-3515 1610);
DISPLAY 0.489362 (-3515 1610);
PAINT MONO (-3515 1610);
FORCEPROP 0 LASTPIN (-3525 1500) $PN AJ53
J 0
(-3515 1510);
DISPLAY 0.489362 (-3515 1510);
PAINT MONO (-3515 1510);
FORCEPROP 0 LASTPIN (-3525 1400) $PN AL53
J 0
(-3515 1410);
DISPLAY 0.489362 (-3515 1410);
PAINT MONO (-3515 1410);
FORCEPROP 0 LASTPIN (-3525 2950) $PN AP40
J 0
(-3515 2960);
DISPLAY 0.489362 (-3515 2960);
PAINT MONO (-3515 2960);
FORCEPROP 0 LASTPIN (-3525 2850) $PN AM40
J 0
(-3515 2860);
DISPLAY 0.489362 (-3515 2860);
PAINT MONO (-3515 2860);
FORCEPROP 0 LASTPIN (-3525 2750) $PN AH40
J 0
(-3515 2760);
DISPLAY 0.489362 (-3515 2760);
PAINT MONO (-3515 2760);
FORCEPROP 0 LASTPIN (-3525 2650) $PN AK40
J 0
(-3515 2660);
DISPLAY 0.489362 (-3515 2660);
PAINT MONO (-3515 2660);
FORCEPROP 0 LASTPIN (-3525 2550) $PN AN43
J 0
(-3515 2560);
DISPLAY 0.489362 (-3515 2560);
PAINT MONO (-3515 2560);
FORCEPROP 0 LASTPIN (-3525 2450) $PN AJ43
J 0
(-3515 2460);
DISPLAY 0.489362 (-3515 2460);
PAINT MONO (-3515 2460);
FORCEPROP 0 LASTPIN (-3525 2350) $PN AL43
J 0
(-3515 2360);
DISPLAY 0.489362 (-3515 2360);
PAINT MONO (-3515 2360);
FORCEPROP 0 LASTPIN (-3525 2250) $PN AN46
J 0
(-3515 2260);
DISPLAY 0.489362 (-3515 2260);
PAINT MONO (-3515 2260);
FORCEPROP 0 LASTPIN (-3525 2150) $PN AJ46
J 0
(-3515 2160);
DISPLAY 0.489362 (-3515 2160);
PAINT MONO (-3515 2160);
FORCEPROP 0 LASTPIN (-3525 2050) $PN AL46
J 0
(-3515 2060);
DISPLAY 0.489362 (-3515 2060);
PAINT MONO (-3515 2060);
FORCEPROP 0 LASTPIN (-3525 1950) $PN AN49
J 0
(-3515 1960);
DISPLAY 0.489362 (-3515 1960);
PAINT MONO (-3515 1960);
FORCEPROP 0 LASTPIN (-3525 1850) $PN AJ49
J 0
(-3515 1860);
DISPLAY 0.489362 (-3515 1860);
PAINT MONO (-3515 1860);
FORCEPROP 0 LASTPIN (-3525 1750) $PN AL49
J 0
(-3515 1760);
DISPLAY 0.489362 (-3515 1760);
PAINT MONO (-3515 1760);
FORCEPROP 0 LASTPIN (-3525 1650) $PN AN52
J 0
(-3515 1660);
DISPLAY 0.489362 (-3515 1660);
PAINT MONO (-3515 1660);
FORCEPROP 0 LASTPIN (-3525 1550) $PN AJ52
J 0
(-3515 1560);
DISPLAY 0.489362 (-3515 1560);
PAINT MONO (-3515 1560);
FORCEPROP 0 LASTPIN (-3525 1450) $PN AL52
J 0
(-3515 1460);
DISPLAY 0.489362 (-3515 1460);
PAINT MONO (-3515 1460);
FORCEPROP 2 LAST PART_TYPE SMLF
J 0
(-5875 3350);
DISPLAY 1.021277 (-5875 3350);
FORCEPROP 1 LAST MATERIAL IO
J 0
(-5870 3182);
DISPLAY 0.489362 (-5870 3182);
PAINT SKYBLUE (-5870 3182);
FORCEPROP 2 LAST VALUE SOCKET6096_13568-001
J 0
(-5875 3250);
DISPLAY 0.489362 (-5875 3250);
PAINT SKYBLUE (-5875 3250);
FORCEPROP 2 LAST CDS_LIB pure_quanta
J 0
(-4775 2200);
DISPLAY INVISIBLE (-4775 2200);
FORCEPROP 1 LAST NEEDS_NO_SIZE TRUE
J 0
(-4775 2200);
DISPLAY 0.723404 (-4775 2200);
PAINT GREEN (-4775 2200);
DISPLAY INVISIBLE (-4775 2200);
FORCEPROP 1 LAST CDS_LMAN_SYM_OUTLINE -1100,950,1100,-950
J 0
(-4775 2200);
DISPLAY 0.468085 (-4775 2200);
PAINT GREEN (-4775 2200);
DISPLAY INVISIBLE (-4775 2200);
FORCEPROP 1 LAST PATH I208
J 0
(-4775 2200);
DISPLAY 0.723404 (-4775 2200);
PAINT GREEN (-4775 2200);
DISPLAY INVISIBLE (-4775 2200);
FORCEPROP 1 LAST PART_NUMBER DGA^6000030
J 0
(-5870 3309);
DISPLAY 0.489362 (-5870 3309);
PAINT SKYBLUE (-5870 3309);
DISPLAY INVISIBLE (-5870 3309);
FORCEADD OFFPAGE..2
(-1825 5900);
FORCEPROP 2 LAST $XR0 50 
J 0
(-1636 5900);
DISPLAY 0.638298 (-1636 5900);
PAINT MONO (-1636 5900);
FORCEPROP 2 LAST CDS_LIB standard
J 0
(-1825 5900);
DISPLAY INVISIBLE (-1825 5900);
FORCEPROP 1 LAST OFFPAGE TRUE
J 0
(-1500 5775);
DISPLAY 0.872340 (-1500 5775);
PAINT GREEN (-1500 5775);
DISPLAY INVISIBLE (-1500 5775);
FORCEPROP 1 LAST COMMENT_BODY TRUE
J 0
(-1870 5805);
DISPLAY 0.872340 (-1870 5805);
PAINT GREEN (-1870 5805);
DISPLAY INVISIBLE (-1870 5805);
FORCEPROP 2 LAST PATH I243
J 0
(-1625 5950);
DISPLAY 1.021277 (-1625 5950);
DISPLAY INVISIBLE (-1625 5950);
FORCEADD OFFPAGE..2
(-1825 5850);
FORCEPROP 2 LAST $XR0 50 
J 0
(-1636 5850);
DISPLAY 0.638298 (-1636 5850);
PAINT MONO (-1636 5850);
FORCEPROP 2 LAST CDS_LIB standard
J 0
(-1825 5850);
DISPLAY INVISIBLE (-1825 5850);
FORCEPROP 1 LAST OFFPAGE TRUE
J 0
(-1500 5725);
DISPLAY 0.872340 (-1500 5725);
PAINT GREEN (-1500 5725);
DISPLAY INVISIBLE (-1500 5725);
FORCEPROP 1 LAST COMMENT_BODY TRUE
J 0
(-1870 5755);
DISPLAY 0.872340 (-1870 5755);
PAINT GREEN (-1870 5755);
DISPLAY INVISIBLE (-1870 5755);
FORCEPROP 2 LAST PATH I244
J 0
(-1625 5900);
DISPLAY 1.021277 (-1625 5900);
DISPLAY INVISIBLE (-1625 5900);
FORCEADD TAP..6
R 2
(-3100 5675);
FORCEPROP 3 LASTPIN (-3150 5675) SIG_NAME GMI_CPU0_G0_CPU1_G2_TX_DP<0>
J 0
(-3140 5685);
DISPLAY 0.659574 (-3140 5685);
PAINT MONO (-3140 5685);
DISPLAY INVISIBLE (-3140 5685);
FORCEPROP 1 LASTPIN (-3150 5675) BN 0
J 2
(-3098 5683);
DISPLAY 0.489362 (-3098 5683);
PAINT MONO (-3098 5683);
FORCEPROP 2 LAST BOM_COST IO_SLOT
J 0
(-3600 5775);
DISPLAY 0.829787 (-3600 5775);
DISPLAY INVISIBLE (-3600 5775);
FORCEPROP 2 LAST CDS_LIB mstr_standard
J 0
(-3100 5675);
DISPLAY INVISIBLE (-3100 5675);
FORCEPROP 2 LAST ROOM RISER1
J 0
(-3600 5725);
DISPLAY 0.829787 (-3600 5725);
PAINT RED (-3600 5725);
DISPLAY INVISIBLE (-3600 5725);
FORCEPROP 1 LAST BODY_TYPE PLUMBING
J 2
(-3100 5625);
DISPLAY 0.702128 (-3100 5625);
PAINT GREEN (-3100 5625);
DISPLAY INVISIBLE (-3100 5625);
FORCEPROP 1 LAST HDL_TAP TRUE
J 2
(-3425 5550);
DISPLAY 0.702128 (-3425 5550);
PAINT GREEN (-3425 5550);
DISPLAY INVISIBLE (-3425 5550);
FORCEPROP 1 LAST PATH I245
J 2
(-3098 5675);
DISPLAY 0.872340 (-3098 5675);
PAINT GREEN (-3098 5675);
DISPLAY INVISIBLE (-3098 5675);
FORCEADD TAP..6
R 2
(-2950 5625);
FORCEPROP 3 LASTPIN (-3000 5625) SIG_NAME GMI_CPU0_G0_CPU1_G2_TX_DN<0>
J 0
(-2990 5635);
DISPLAY 0.659574 (-2990 5635);
PAINT MONO (-2990 5635);
DISPLAY INVISIBLE (-2990 5635);
FORCEPROP 1 LASTPIN (-3000 5625) BN 0
J 2
(-2948 5633);
DISPLAY 0.489362 (-2948 5633);
PAINT MONO (-2948 5633);
FORCEPROP 2 LAST BOM_COST IO_SLOT
J 0
(-3450 5725);
DISPLAY 0.829787 (-3450 5725);
DISPLAY INVISIBLE (-3450 5725);
FORCEPROP 2 LAST CDS_LIB mstr_standard
J 0
(-2950 5625);
DISPLAY INVISIBLE (-2950 5625);
FORCEPROP 2 LAST ROOM RISER1
J 0
(-3450 5675);
DISPLAY 0.829787 (-3450 5675);
PAINT RED (-3450 5675);
DISPLAY INVISIBLE (-3450 5675);
FORCEPROP 1 LAST BODY_TYPE PLUMBING
J 2
(-2950 5575);
DISPLAY 0.702128 (-2950 5575);
PAINT GREEN (-2950 5575);
DISPLAY INVISIBLE (-2950 5575);
FORCEPROP 1 LAST HDL_TAP TRUE
J 2
(-3275 5500);
DISPLAY 0.702128 (-3275 5500);
PAINT GREEN (-3275 5500);
DISPLAY INVISIBLE (-3275 5500);
FORCEPROP 1 LAST PATH I246
J 2
(-2948 5625);
DISPLAY 0.872340 (-2948 5625);
PAINT GREEN (-2948 5625);
DISPLAY INVISIBLE (-2948 5625);
FORCEADD TAP..6
R 2
(-2950 5525);
FORCEPROP 3 LASTPIN (-3000 5525) SIG_NAME GMI_CPU0_G0_CPU1_G2_TX_DN<1>
J 0
(-2990 5535);
DISPLAY 0.659574 (-2990 5535);
PAINT MONO (-2990 5535);
DISPLAY INVISIBLE (-2990 5535);
FORCEPROP 1 LASTPIN (-3000 5525) BN 1
J 2
(-2948 5533);
DISPLAY 0.489362 (-2948 5533);
PAINT MONO (-2948 5533);
FORCEPROP 2 LAST BOM_COST IO_SLOT
J 0
(-3450 5625);
DISPLAY 0.829787 (-3450 5625);
DISPLAY INVISIBLE (-3450 5625);
FORCEPROP 2 LAST CDS_LIB mstr_standard
J 0
(-2950 5525);
DISPLAY INVISIBLE (-2950 5525);
FORCEPROP 2 LAST ROOM RISER1
J 0
(-3450 5575);
DISPLAY 0.829787 (-3450 5575);
PAINT RED (-3450 5575);
DISPLAY INVISIBLE (-3450 5575);
FORCEPROP 1 LAST BODY_TYPE PLUMBING
J 2
(-2950 5475);
DISPLAY 0.702128 (-2950 5475);
PAINT GREEN (-2950 5475);
DISPLAY INVISIBLE (-2950 5475);
FORCEPROP 1 LAST HDL_TAP TRUE
J 2
(-3275 5400);
DISPLAY 0.702128 (-3275 5400);
PAINT GREEN (-3275 5400);
DISPLAY INVISIBLE (-3275 5400);
FORCEPROP 1 LAST PATH I247
J 2
(-2948 5525);
DISPLAY 0.872340 (-2948 5525);
PAINT GREEN (-2948 5525);
DISPLAY INVISIBLE (-2948 5525);
FORCEADD TAP..6
R 2
(-2950 5425);
FORCEPROP 3 LASTPIN (-3000 5425) SIG_NAME GMI_CPU0_G0_CPU1_G2_TX_DN<2>
J 0
(-2990 5435);
DISPLAY 0.659574 (-2990 5435);
PAINT MONO (-2990 5435);
DISPLAY INVISIBLE (-2990 5435);
FORCEPROP 1 LASTPIN (-3000 5425) BN 2
J 2
(-2948 5433);
DISPLAY 0.489362 (-2948 5433);
PAINT MONO (-2948 5433);
FORCEPROP 2 LAST CDS_LIB standard
J 0
(-2950 5425);
DISPLAY INVISIBLE (-2950 5425);
FORCEPROP 2 LAST BOM_COST IO_SLOT
J 0
(-3450 5525);
DISPLAY 0.829787 (-3450 5525);
DISPLAY INVISIBLE (-3450 5525);
FORCEPROP 2 LAST ROOM RISER1
J 0
(-3450 5475);
DISPLAY 0.829787 (-3450 5475);
PAINT RED (-3450 5475);
DISPLAY INVISIBLE (-3450 5475);
FORCEPROP 1 LAST BODY_TYPE PLUMBING
J 2
(-2950 5375);
DISPLAY 0.702128 (-2950 5375);
PAINT GREEN (-2950 5375);
DISPLAY INVISIBLE (-2950 5375);
FORCEPROP 1 LAST HDL_TAP TRUE
J 2
(-3275 5300);
DISPLAY 0.702128 (-3275 5300);
PAINT GREEN (-3275 5300);
DISPLAY INVISIBLE (-3275 5300);
FORCEPROP 1 LAST PATH I248
J 2
(-2948 5425);
DISPLAY 0.872340 (-2948 5425);
PAINT GREEN (-2948 5425);
DISPLAY INVISIBLE (-2948 5425);
FORCEADD TAP..6
R 2
(-3100 5475);
FORCEPROP 3 LASTPIN (-3150 5475) SIG_NAME GMI_CPU0_G0_CPU1_G2_TX_DP<2>
J 0
(-3140 5485);
DISPLAY 0.659574 (-3140 5485);
PAINT MONO (-3140 5485);
DISPLAY INVISIBLE (-3140 5485);
FORCEPROP 1 LASTPIN (-3150 5475) BN 2
J 2
(-3098 5483);
DISPLAY 0.489362 (-3098 5483);
PAINT MONO (-3098 5483);
FORCEPROP 2 LAST CDS_LIB standard
J 0
(-3100 5475);
DISPLAY INVISIBLE (-3100 5475);
FORCEPROP 2 LAST BOM_COST IO_SLOT
J 0
(-3600 5575);
DISPLAY 0.829787 (-3600 5575);
DISPLAY INVISIBLE (-3600 5575);
FORCEPROP 2 LAST ROOM RISER1
J 0
(-3600 5525);
DISPLAY 0.829787 (-3600 5525);
PAINT RED (-3600 5525);
DISPLAY INVISIBLE (-3600 5525);
FORCEPROP 1 LAST BODY_TYPE PLUMBING
J 2
(-3100 5425);
DISPLAY 0.702128 (-3100 5425);
PAINT GREEN (-3100 5425);
DISPLAY INVISIBLE (-3100 5425);
FORCEPROP 1 LAST HDL_TAP TRUE
J 2
(-3425 5350);
DISPLAY 0.702128 (-3425 5350);
PAINT GREEN (-3425 5350);
DISPLAY INVISIBLE (-3425 5350);
FORCEPROP 1 LAST PATH I249
J 2
(-3098 5475);
DISPLAY 0.872340 (-3098 5475);
PAINT GREEN (-3098 5475);
DISPLAY INVISIBLE (-3098 5475);
FORCEADD TAP..6
R 2
(-3100 5575);
FORCEPROP 3 LASTPIN (-3150 5575) SIG_NAME GMI_CPU0_G0_CPU1_G2_TX_DP<1>
J 0
(-3140 5585);
DISPLAY 0.659574 (-3140 5585);
PAINT MONO (-3140 5585);
DISPLAY INVISIBLE (-3140 5585);
FORCEPROP 1 LASTPIN (-3150 5575) BN 1
J 2
(-3098 5583);
DISPLAY 0.489362 (-3098 5583);
PAINT MONO (-3098 5583);
FORCEPROP 2 LAST CDS_LIB mstr_standard
J 0
(-3100 5575);
DISPLAY INVISIBLE (-3100 5575);
FORCEPROP 2 LAST BOM_COST IO_SLOT
J 0
(-3600 5675);
DISPLAY 0.829787 (-3600 5675);
DISPLAY INVISIBLE (-3600 5675);
FORCEPROP 2 LAST ROOM RISER1
J 0
(-3600 5625);
DISPLAY 0.829787 (-3600 5625);
PAINT RED (-3600 5625);
DISPLAY INVISIBLE (-3600 5625);
FORCEPROP 1 LAST BODY_TYPE PLUMBING
J 2
(-3100 5525);
DISPLAY 0.702128 (-3100 5525);
PAINT GREEN (-3100 5525);
DISPLAY INVISIBLE (-3100 5525);
FORCEPROP 1 LAST HDL_TAP TRUE
J 2
(-3425 5450);
DISPLAY 0.702128 (-3425 5450);
PAINT GREEN (-3425 5450);
DISPLAY INVISIBLE (-3425 5450);
FORCEPROP 1 LAST PATH I250
J 2
(-3098 5575);
DISPLAY 0.872340 (-3098 5575);
PAINT GREEN (-3098 5575);
DISPLAY INVISIBLE (-3098 5575);
FORCEADD TAP..6
R 2
(-2950 5325);
FORCEPROP 3 LASTPIN (-3000 5325) SIG_NAME GMI_CPU0_G0_CPU1_G2_TX_DN<3>
J 0
(-2990 5335);
DISPLAY 0.659574 (-2990 5335);
PAINT MONO (-2990 5335);
DISPLAY INVISIBLE (-2990 5335);
FORCEPROP 1 LASTPIN (-3000 5325) BN 3
J 2
(-2948 5333);
DISPLAY 0.489362 (-2948 5333);
PAINT MONO (-2948 5333);
FORCEPROP 2 LAST CDS_LIB standard
J 0
(-2950 5325);
DISPLAY INVISIBLE (-2950 5325);
FORCEPROP 2 LAST BOM_COST IO_SLOT
J 0
(-3450 5425);
DISPLAY 0.829787 (-3450 5425);
DISPLAY INVISIBLE (-3450 5425);
FORCEPROP 2 LAST ROOM RISER1
J 0
(-3450 5375);
DISPLAY 0.829787 (-3450 5375);
PAINT RED (-3450 5375);
DISPLAY INVISIBLE (-3450 5375);
FORCEPROP 1 LAST BODY_TYPE PLUMBING
J 2
(-2950 5275);
DISPLAY 0.702128 (-2950 5275);
PAINT GREEN (-2950 5275);
DISPLAY INVISIBLE (-2950 5275);
FORCEPROP 1 LAST HDL_TAP TRUE
J 2
(-3275 5200);
DISPLAY 0.702128 (-3275 5200);
PAINT GREEN (-3275 5200);
DISPLAY INVISIBLE (-3275 5200);
FORCEPROP 1 LAST PATH I251
J 2
(-2948 5325);
DISPLAY 0.872340 (-2948 5325);
PAINT GREEN (-2948 5325);
DISPLAY INVISIBLE (-2948 5325);
FORCEADD TAP..6
R 2
(-2950 5225);
FORCEPROP 3 LASTPIN (-3000 5225) SIG_NAME GMI_CPU0_G0_CPU1_G2_TX_DN<4>
J 0
(-2990 5235);
DISPLAY 0.659574 (-2990 5235);
PAINT MONO (-2990 5235);
DISPLAY INVISIBLE (-2990 5235);
FORCEPROP 1 LASTPIN (-3000 5225) BN 4
J 2
(-2948 5233);
DISPLAY 0.489362 (-2948 5233);
PAINT MONO (-2948 5233);
FORCEPROP 2 LAST CDS_LIB standard
J 0
(-2950 5225);
DISPLAY INVISIBLE (-2950 5225);
FORCEPROP 2 LAST BOM_COST IO_SLOT
J 0
(-3450 5325);
DISPLAY 0.829787 (-3450 5325);
DISPLAY INVISIBLE (-3450 5325);
FORCEPROP 2 LAST ROOM RISER1
J 0
(-3450 5275);
DISPLAY 0.829787 (-3450 5275);
PAINT RED (-3450 5275);
DISPLAY INVISIBLE (-3450 5275);
FORCEPROP 1 LAST BODY_TYPE PLUMBING
J 2
(-2950 5175);
DISPLAY 0.702128 (-2950 5175);
PAINT GREEN (-2950 5175);
DISPLAY INVISIBLE (-2950 5175);
FORCEPROP 1 LAST HDL_TAP TRUE
J 2
(-3275 5100);
DISPLAY 0.702128 (-3275 5100);
PAINT GREEN (-3275 5100);
DISPLAY INVISIBLE (-3275 5100);
FORCEPROP 1 LAST PATH I252
J 2
(-2948 5225);
DISPLAY 0.872340 (-2948 5225);
PAINT GREEN (-2948 5225);
DISPLAY INVISIBLE (-2948 5225);
FORCEADD TAP..6
R 2
(-2950 5125);
FORCEPROP 3 LASTPIN (-3000 5125) SIG_NAME GMI_CPU0_G0_CPU1_G2_TX_DN<5>
J 0
(-2990 5135);
DISPLAY 0.659574 (-2990 5135);
PAINT MONO (-2990 5135);
DISPLAY INVISIBLE (-2990 5135);
FORCEPROP 1 LASTPIN (-3000 5125) BN 5
J 2
(-2948 5133);
DISPLAY 0.489362 (-2948 5133);
PAINT MONO (-2948 5133);
FORCEPROP 2 LAST CDS_LIB standard
J 0
(-2950 5125);
DISPLAY INVISIBLE (-2950 5125);
FORCEPROP 2 LAST BOM_COST IO_SLOT
J 0
(-3450 5225);
DISPLAY 0.829787 (-3450 5225);
DISPLAY INVISIBLE (-3450 5225);
FORCEPROP 2 LAST ROOM RISER1
J 0
(-3450 5175);
DISPLAY 0.829787 (-3450 5175);
PAINT RED (-3450 5175);
DISPLAY INVISIBLE (-3450 5175);
FORCEPROP 1 LAST BODY_TYPE PLUMBING
J 2
(-2950 5075);
DISPLAY 0.702128 (-2950 5075);
PAINT GREEN (-2950 5075);
DISPLAY INVISIBLE (-2950 5075);
FORCEPROP 1 LAST HDL_TAP TRUE
J 2
(-3275 5000);
DISPLAY 0.702128 (-3275 5000);
PAINT GREEN (-3275 5000);
DISPLAY INVISIBLE (-3275 5000);
FORCEPROP 1 LAST PATH I253
J 2
(-2948 5125);
DISPLAY 0.872340 (-2948 5125);
PAINT GREEN (-2948 5125);
DISPLAY INVISIBLE (-2948 5125);
FORCEADD TAP..6
R 2
(-3100 5275);
FORCEPROP 3 LASTPIN (-3150 5275) SIG_NAME GMI_CPU0_G0_CPU1_G2_TX_DP<4>
J 0
(-3140 5285);
DISPLAY 0.659574 (-3140 5285);
PAINT MONO (-3140 5285);
DISPLAY INVISIBLE (-3140 5285);
FORCEPROP 1 LASTPIN (-3150 5275) BN 4
J 2
(-3098 5283);
DISPLAY 0.489362 (-3098 5283);
PAINT MONO (-3098 5283);
FORCEPROP 2 LAST BOM_COST IO_SLOT
J 0
(-3600 5375);
DISPLAY 0.829787 (-3600 5375);
DISPLAY INVISIBLE (-3600 5375);
FORCEPROP 2 LAST CDS_LIB standard
J 0
(-3100 5275);
DISPLAY INVISIBLE (-3100 5275);
FORCEPROP 2 LAST ROOM RISER1
J 0
(-3600 5325);
DISPLAY 0.829787 (-3600 5325);
PAINT RED (-3600 5325);
DISPLAY INVISIBLE (-3600 5325);
FORCEPROP 1 LAST BODY_TYPE PLUMBING
J 2
(-3100 5225);
DISPLAY 0.702128 (-3100 5225);
PAINT GREEN (-3100 5225);
DISPLAY INVISIBLE (-3100 5225);
FORCEPROP 1 LAST HDL_TAP TRUE
J 2
(-3425 5150);
DISPLAY 0.702128 (-3425 5150);
PAINT GREEN (-3425 5150);
DISPLAY INVISIBLE (-3425 5150);
FORCEPROP 1 LAST PATH I254
J 2
(-3098 5275);
DISPLAY 0.872340 (-3098 5275);
PAINT GREEN (-3098 5275);
DISPLAY INVISIBLE (-3098 5275);
FORCEADD TAP..6
R 2
(-3100 5175);
FORCEPROP 3 LASTPIN (-3150 5175) SIG_NAME GMI_CPU0_G0_CPU1_G2_TX_DP<5>
J 0
(-3140 5185);
DISPLAY 0.659574 (-3140 5185);
PAINT MONO (-3140 5185);
DISPLAY INVISIBLE (-3140 5185);
FORCEPROP 1 LASTPIN (-3150 5175) BN 5
J 2
(-3098 5183);
DISPLAY 0.489362 (-3098 5183);
PAINT MONO (-3098 5183);
FORCEPROP 2 LAST BOM_COST IO_SLOT
J 0
(-3600 5275);
DISPLAY 0.829787 (-3600 5275);
DISPLAY INVISIBLE (-3600 5275);
FORCEPROP 2 LAST CDS_LIB standard
J 0
(-3100 5175);
DISPLAY INVISIBLE (-3100 5175);
FORCEPROP 2 LAST ROOM RISER1
J 0
(-3600 5225);
DISPLAY 0.829787 (-3600 5225);
PAINT RED (-3600 5225);
DISPLAY INVISIBLE (-3600 5225);
FORCEPROP 1 LAST BODY_TYPE PLUMBING
J 2
(-3100 5125);
DISPLAY 0.702128 (-3100 5125);
PAINT GREEN (-3100 5125);
DISPLAY INVISIBLE (-3100 5125);
FORCEPROP 1 LAST HDL_TAP TRUE
J 2
(-3425 5050);
DISPLAY 0.702128 (-3425 5050);
PAINT GREEN (-3425 5050);
DISPLAY INVISIBLE (-3425 5050);
FORCEPROP 1 LAST PATH I255
J 2
(-3098 5175);
DISPLAY 0.872340 (-3098 5175);
PAINT GREEN (-3098 5175);
DISPLAY INVISIBLE (-3098 5175);
FORCEADD TAP..6
R 2
(-3100 5375);
FORCEPROP 3 LASTPIN (-3150 5375) SIG_NAME GMI_CPU0_G0_CPU1_G2_TX_DP<3>
J 0
(-3140 5385);
DISPLAY 0.659574 (-3140 5385);
PAINT MONO (-3140 5385);
DISPLAY INVISIBLE (-3140 5385);
FORCEPROP 1 LASTPIN (-3150 5375) BN 3
J 2
(-3098 5383);
DISPLAY 0.489362 (-3098 5383);
PAINT MONO (-3098 5383);
FORCEPROP 2 LAST BOM_COST IO_SLOT
J 0
(-3600 5475);
DISPLAY 0.829787 (-3600 5475);
DISPLAY INVISIBLE (-3600 5475);
FORCEPROP 2 LAST CDS_LIB standard
J 0
(-3100 5375);
DISPLAY INVISIBLE (-3100 5375);
FORCEPROP 2 LAST ROOM RISER1
J 0
(-3600 5425);
DISPLAY 0.829787 (-3600 5425);
PAINT RED (-3600 5425);
DISPLAY INVISIBLE (-3600 5425);
FORCEPROP 1 LAST BODY_TYPE PLUMBING
J 2
(-3100 5325);
DISPLAY 0.702128 (-3100 5325);
PAINT GREEN (-3100 5325);
DISPLAY INVISIBLE (-3100 5325);
FORCEPROP 1 LAST HDL_TAP TRUE
J 2
(-3425 5250);
DISPLAY 0.702128 (-3425 5250);
PAINT GREEN (-3425 5250);
DISPLAY INVISIBLE (-3425 5250);
FORCEPROP 1 LAST PATH I256
J 2
(-3098 5375);
DISPLAY 0.872340 (-3098 5375);
PAINT GREEN (-3098 5375);
DISPLAY INVISIBLE (-3098 5375);
FORCEADD TAP..6
R 2
(-2950 5025);
FORCEPROP 3 LASTPIN (-3000 5025) SIG_NAME GMI_CPU0_G0_CPU1_G2_TX_DN<6>
J 0
(-2990 5035);
DISPLAY 0.659574 (-2990 5035);
PAINT MONO (-2990 5035);
DISPLAY INVISIBLE (-2990 5035);
FORCEPROP 1 LASTPIN (-3000 5025) BN 6
J 2
(-2948 5033);
DISPLAY 0.489362 (-2948 5033);
PAINT MONO (-2948 5033);
FORCEPROP 2 LAST CDS_LIB standard
J 0
(-2950 5025);
DISPLAY INVISIBLE (-2950 5025);
FORCEPROP 2 LAST BOM_COST IO_SLOT
J 0
(-3450 5125);
DISPLAY 0.829787 (-3450 5125);
DISPLAY INVISIBLE (-3450 5125);
FORCEPROP 2 LAST ROOM RISER1
J 0
(-3450 5075);
DISPLAY 0.829787 (-3450 5075);
PAINT RED (-3450 5075);
DISPLAY INVISIBLE (-3450 5075);
FORCEPROP 1 LAST BODY_TYPE PLUMBING
J 2
(-2950 4975);
DISPLAY 0.702128 (-2950 4975);
PAINT GREEN (-2950 4975);
DISPLAY INVISIBLE (-2950 4975);
FORCEPROP 1 LAST HDL_TAP TRUE
J 2
(-3275 4900);
DISPLAY 0.702128 (-3275 4900);
PAINT GREEN (-3275 4900);
DISPLAY INVISIBLE (-3275 4900);
FORCEPROP 1 LAST PATH I257
J 2
(-2948 5025);
DISPLAY 0.872340 (-2948 5025);
PAINT GREEN (-2948 5025);
DISPLAY INVISIBLE (-2948 5025);
FORCEADD TAP..6
R 2
(-2950 4925);
FORCEPROP 3 LASTPIN (-3000 4925) SIG_NAME GMI_CPU0_G0_CPU1_G2_TX_DN<7>
J 0
(-2990 4935);
DISPLAY 0.659574 (-2990 4935);
PAINT MONO (-2990 4935);
DISPLAY INVISIBLE (-2990 4935);
FORCEPROP 1 LASTPIN (-3000 4925) BN 7
J 2
(-2948 4933);
DISPLAY 0.489362 (-2948 4933);
PAINT MONO (-2948 4933);
FORCEPROP 2 LAST CDS_LIB standard
J 0
(-2950 4925);
DISPLAY INVISIBLE (-2950 4925);
FORCEPROP 2 LAST BOM_COST IO_SLOT
J 0
(-3450 5025);
DISPLAY 0.829787 (-3450 5025);
DISPLAY INVISIBLE (-3450 5025);
FORCEPROP 2 LAST ROOM RISER1
J 0
(-3450 4975);
DISPLAY 0.829787 (-3450 4975);
PAINT RED (-3450 4975);
DISPLAY INVISIBLE (-3450 4975);
FORCEPROP 1 LAST BODY_TYPE PLUMBING
J 2
(-2950 4875);
DISPLAY 0.702128 (-2950 4875);
PAINT GREEN (-2950 4875);
DISPLAY INVISIBLE (-2950 4875);
FORCEPROP 1 LAST HDL_TAP TRUE
J 2
(-3275 4800);
DISPLAY 0.702128 (-3275 4800);
PAINT GREEN (-3275 4800);
DISPLAY INVISIBLE (-3275 4800);
FORCEPROP 1 LAST PATH I258
J 2
(-2948 4925);
DISPLAY 0.872340 (-2948 4925);
PAINT GREEN (-2948 4925);
DISPLAY INVISIBLE (-2948 4925);
FORCEADD TAP..6
R 2
(-3100 4875);
FORCEPROP 3 LASTPIN (-3150 4875) SIG_NAME GMI_CPU0_G0_CPU1_G2_TX_DP<8>
J 0
(-3140 4885);
DISPLAY 0.659574 (-3140 4885);
PAINT MONO (-3140 4885);
DISPLAY INVISIBLE (-3140 4885);
FORCEPROP 1 LASTPIN (-3150 4875) BN 8
J 2
(-3098 4883);
DISPLAY 0.489362 (-3098 4883);
PAINT MONO (-3098 4883);
FORCEPROP 2 LAST BOM_COST IO_SLOT
J 0
(-3600 4975);
DISPLAY 0.829787 (-3600 4975);
DISPLAY INVISIBLE (-3600 4975);
FORCEPROP 2 LAST CDS_LIB standard
J 0
(-3100 4875);
DISPLAY INVISIBLE (-3100 4875);
FORCEPROP 2 LAST ROOM RISER1
J 0
(-3600 4925);
DISPLAY 0.829787 (-3600 4925);
PAINT RED (-3600 4925);
DISPLAY INVISIBLE (-3600 4925);
FORCEPROP 1 LAST BODY_TYPE PLUMBING
J 2
(-3100 4825);
DISPLAY 0.702128 (-3100 4825);
PAINT GREEN (-3100 4825);
DISPLAY INVISIBLE (-3100 4825);
FORCEPROP 1 LAST HDL_TAP TRUE
J 2
(-3425 4750);
DISPLAY 0.702128 (-3425 4750);
PAINT GREEN (-3425 4750);
DISPLAY INVISIBLE (-3425 4750);
FORCEPROP 1 LAST PATH I259
J 2
(-3098 4875);
DISPLAY 0.872340 (-3098 4875);
PAINT GREEN (-3098 4875);
DISPLAY INVISIBLE (-3098 4875);
FORCEADD TAP..6
R 2
(-3100 4975);
FORCEPROP 3 LASTPIN (-3150 4975) SIG_NAME GMI_CPU0_G0_CPU1_G2_TX_DP<7>
J 0
(-3140 4985);
DISPLAY 0.659574 (-3140 4985);
PAINT MONO (-3140 4985);
DISPLAY INVISIBLE (-3140 4985);
FORCEPROP 1 LASTPIN (-3150 4975) BN 7
J 2
(-3098 4983);
DISPLAY 0.489362 (-3098 4983);
PAINT MONO (-3098 4983);
FORCEPROP 2 LAST BOM_COST IO_SLOT
J 0
(-3600 5075);
DISPLAY 0.829787 (-3600 5075);
DISPLAY INVISIBLE (-3600 5075);
FORCEPROP 2 LAST CDS_LIB standard
J 0
(-3100 4975);
DISPLAY INVISIBLE (-3100 4975);
FORCEPROP 2 LAST ROOM RISER1
J 0
(-3600 5025);
DISPLAY 0.829787 (-3600 5025);
PAINT RED (-3600 5025);
DISPLAY INVISIBLE (-3600 5025);
FORCEPROP 1 LAST BODY_TYPE PLUMBING
J 2
(-3100 4925);
DISPLAY 0.702128 (-3100 4925);
PAINT GREEN (-3100 4925);
DISPLAY INVISIBLE (-3100 4925);
FORCEPROP 1 LAST HDL_TAP TRUE
J 2
(-3425 4850);
DISPLAY 0.702128 (-3425 4850);
PAINT GREEN (-3425 4850);
DISPLAY INVISIBLE (-3425 4850);
FORCEPROP 1 LAST PATH I260
J 2
(-3098 4975);
DISPLAY 0.872340 (-3098 4975);
PAINT GREEN (-3098 4975);
DISPLAY INVISIBLE (-3098 4975);
FORCEADD TAP..6
R 2
(-3100 5075);
FORCEPROP 3 LASTPIN (-3150 5075) SIG_NAME GMI_CPU0_G0_CPU1_G2_TX_DP<6>
J 0
(-3140 5085);
DISPLAY 0.659574 (-3140 5085);
PAINT MONO (-3140 5085);
DISPLAY INVISIBLE (-3140 5085);
FORCEPROP 1 LASTPIN (-3150 5075) BN 6
J 2
(-3098 5083);
DISPLAY 0.489362 (-3098 5083);
PAINT MONO (-3098 5083);
FORCEPROP 2 LAST BOM_COST IO_SLOT
J 0
(-3600 5175);
DISPLAY 0.829787 (-3600 5175);
DISPLAY INVISIBLE (-3600 5175);
FORCEPROP 2 LAST CDS_LIB standard
J 0
(-3100 5075);
DISPLAY INVISIBLE (-3100 5075);
FORCEPROP 2 LAST ROOM RISER1
J 0
(-3600 5125);
DISPLAY 0.829787 (-3600 5125);
PAINT RED (-3600 5125);
DISPLAY INVISIBLE (-3600 5125);
FORCEPROP 1 LAST BODY_TYPE PLUMBING
J 2
(-3100 5025);
DISPLAY 0.702128 (-3100 5025);
PAINT GREEN (-3100 5025);
DISPLAY INVISIBLE (-3100 5025);
FORCEPROP 1 LAST HDL_TAP TRUE
J 2
(-3425 4950);
DISPLAY 0.702128 (-3425 4950);
PAINT GREEN (-3425 4950);
DISPLAY INVISIBLE (-3425 4950);
FORCEPROP 1 LAST PATH I261
J 2
(-3098 5075);
DISPLAY 0.872340 (-3098 5075);
PAINT GREEN (-3098 5075);
DISPLAY INVISIBLE (-3098 5075);
FORCEADD TAP..6
R 2
(-2950 4825);
FORCEPROP 3 LASTPIN (-3000 4825) SIG_NAME GMI_CPU0_G0_CPU1_G2_TX_DN<8>
J 0
(-2990 4835);
DISPLAY 0.659574 (-2990 4835);
PAINT MONO (-2990 4835);
DISPLAY INVISIBLE (-2990 4835);
FORCEPROP 1 LASTPIN (-3000 4825) BN 8
J 2
(-2948 4833);
DISPLAY 0.489362 (-2948 4833);
PAINT MONO (-2948 4833);
FORCEPROP 2 LAST CDS_LIB standard
J 0
(-2950 4825);
DISPLAY INVISIBLE (-2950 4825);
FORCEPROP 2 LAST BOM_COST IO_SLOT
J 0
(-3450 4925);
DISPLAY 0.829787 (-3450 4925);
DISPLAY INVISIBLE (-3450 4925);
FORCEPROP 2 LAST ROOM RISER1
J 0
(-3450 4875);
DISPLAY 0.829787 (-3450 4875);
PAINT RED (-3450 4875);
DISPLAY INVISIBLE (-3450 4875);
FORCEPROP 1 LAST BODY_TYPE PLUMBING
J 2
(-2950 4775);
DISPLAY 0.702128 (-2950 4775);
PAINT GREEN (-2950 4775);
DISPLAY INVISIBLE (-2950 4775);
FORCEPROP 1 LAST HDL_TAP TRUE
J 2
(-3275 4700);
DISPLAY 0.702128 (-3275 4700);
PAINT GREEN (-3275 4700);
DISPLAY INVISIBLE (-3275 4700);
FORCEPROP 1 LAST PATH I262
J 2
(-2948 4825);
DISPLAY 0.872340 (-2948 4825);
PAINT GREEN (-2948 4825);
DISPLAY INVISIBLE (-2948 4825);
FORCEADD TAP..6
R 2
(-2950 4725);
FORCEPROP 3 LASTPIN (-3000 4725) SIG_NAME GMI_CPU0_G0_CPU1_G2_TX_DN<9>
J 0
(-2990 4735);
DISPLAY 0.659574 (-2990 4735);
PAINT MONO (-2990 4735);
DISPLAY INVISIBLE (-2990 4735);
FORCEPROP 1 LASTPIN (-3000 4725) BN 9
J 2
(-2948 4733);
DISPLAY 0.489362 (-2948 4733);
PAINT MONO (-2948 4733);
FORCEPROP 2 LAST CDS_LIB standard
J 0
(-2950 4725);
DISPLAY INVISIBLE (-2950 4725);
FORCEPROP 2 LAST BOM_COST IO_SLOT
J 0
(-3450 4825);
DISPLAY 0.829787 (-3450 4825);
DISPLAY INVISIBLE (-3450 4825);
FORCEPROP 2 LAST ROOM RISER1
J 0
(-3450 4775);
DISPLAY 0.829787 (-3450 4775);
PAINT RED (-3450 4775);
DISPLAY INVISIBLE (-3450 4775);
FORCEPROP 1 LAST BODY_TYPE PLUMBING
J 2
(-2950 4675);
DISPLAY 0.702128 (-2950 4675);
PAINT GREEN (-2950 4675);
DISPLAY INVISIBLE (-2950 4675);
FORCEPROP 1 LAST HDL_TAP TRUE
J 2
(-3275 4600);
DISPLAY 0.702128 (-3275 4600);
PAINT GREEN (-3275 4600);
DISPLAY INVISIBLE (-3275 4600);
FORCEPROP 1 LAST PATH I263
J 2
(-2948 4725);
DISPLAY 0.872340 (-2948 4725);
PAINT GREEN (-2948 4725);
DISPLAY INVISIBLE (-2948 4725);
FORCEADD TAP..6
R 2
(-2950 4625);
FORCEPROP 3 LASTPIN (-3000 4625) SIG_NAME GMI_CPU0_G0_CPU1_G2_TX_DN<10>
J 0
(-2990 4635);
DISPLAY 0.659574 (-2990 4635);
PAINT MONO (-2990 4635);
DISPLAY INVISIBLE (-2990 4635);
FORCEPROP 1 LASTPIN (-3000 4625) BN 10
J 2
(-2948 4633);
DISPLAY 0.489362 (-2948 4633);
PAINT MONO (-2948 4633);
FORCEPROP 2 LAST CDS_LIB standard
J 0
(-2950 4625);
DISPLAY INVISIBLE (-2950 4625);
FORCEPROP 2 LAST BOM_COST IO_SLOT
J 0
(-3450 4725);
DISPLAY 0.829787 (-3450 4725);
DISPLAY INVISIBLE (-3450 4725);
FORCEPROP 2 LAST ROOM RISER1
J 0
(-3450 4675);
DISPLAY 0.829787 (-3450 4675);
PAINT RED (-3450 4675);
DISPLAY INVISIBLE (-3450 4675);
FORCEPROP 1 LAST BODY_TYPE PLUMBING
J 2
(-2950 4575);
DISPLAY 0.702128 (-2950 4575);
PAINT GREEN (-2950 4575);
DISPLAY INVISIBLE (-2950 4575);
FORCEPROP 1 LAST HDL_TAP TRUE
J 2
(-3275 4500);
DISPLAY 0.702128 (-3275 4500);
PAINT GREEN (-3275 4500);
DISPLAY INVISIBLE (-3275 4500);
FORCEPROP 1 LAST PATH I264
J 2
(-2948 4625);
DISPLAY 0.872340 (-2948 4625);
PAINT GREEN (-2948 4625);
DISPLAY INVISIBLE (-2948 4625);
FORCEADD TAP..6
R 2
(-3100 4675);
FORCEPROP 3 LASTPIN (-3150 4675) SIG_NAME GMI_CPU0_G0_CPU1_G2_TX_DP<10>
J 0
(-3140 4685);
DISPLAY 0.659574 (-3140 4685);
PAINT MONO (-3140 4685);
DISPLAY INVISIBLE (-3140 4685);
FORCEPROP 1 LASTPIN (-3150 4675) BN 10
J 2
(-3098 4683);
DISPLAY 0.489362 (-3098 4683);
PAINT MONO (-3098 4683);
FORCEPROP 2 LAST BOM_COST IO_SLOT
J 0
(-3600 4775);
DISPLAY 0.829787 (-3600 4775);
DISPLAY INVISIBLE (-3600 4775);
FORCEPROP 2 LAST CDS_LIB standard
J 0
(-3100 4675);
DISPLAY INVISIBLE (-3100 4675);
FORCEPROP 2 LAST ROOM RISER1
J 0
(-3600 4725);
DISPLAY 0.829787 (-3600 4725);
PAINT RED (-3600 4725);
DISPLAY INVISIBLE (-3600 4725);
FORCEPROP 1 LAST BODY_TYPE PLUMBING
J 2
(-3100 4625);
DISPLAY 0.702128 (-3100 4625);
PAINT GREEN (-3100 4625);
DISPLAY INVISIBLE (-3100 4625);
FORCEPROP 1 LAST HDL_TAP TRUE
J 2
(-3425 4550);
DISPLAY 0.702128 (-3425 4550);
PAINT GREEN (-3425 4550);
DISPLAY INVISIBLE (-3425 4550);
FORCEPROP 1 LAST PATH I265
J 2
(-3098 4675);
DISPLAY 0.872340 (-3098 4675);
PAINT GREEN (-3098 4675);
DISPLAY INVISIBLE (-3098 4675);
FORCEADD TAP..6
R 2
(-3100 4775);
FORCEPROP 3 LASTPIN (-3150 4775) SIG_NAME GMI_CPU0_G0_CPU1_G2_TX_DP<9>
J 0
(-3140 4785);
DISPLAY 0.659574 (-3140 4785);
PAINT MONO (-3140 4785);
DISPLAY INVISIBLE (-3140 4785);
FORCEPROP 1 LASTPIN (-3150 4775) BN 9
J 2
(-3098 4783);
DISPLAY 0.489362 (-3098 4783);
PAINT MONO (-3098 4783);
FORCEPROP 2 LAST BOM_COST IO_SLOT
J 0
(-3600 4875);
DISPLAY 0.829787 (-3600 4875);
DISPLAY INVISIBLE (-3600 4875);
FORCEPROP 2 LAST CDS_LIB standard
J 0
(-3100 4775);
DISPLAY INVISIBLE (-3100 4775);
FORCEPROP 2 LAST ROOM RISER1
J 0
(-3600 4825);
DISPLAY 0.829787 (-3600 4825);
PAINT RED (-3600 4825);
DISPLAY INVISIBLE (-3600 4825);
FORCEPROP 1 LAST BODY_TYPE PLUMBING
J 2
(-3100 4725);
DISPLAY 0.702128 (-3100 4725);
PAINT GREEN (-3100 4725);
DISPLAY INVISIBLE (-3100 4725);
FORCEPROP 1 LAST HDL_TAP TRUE
J 2
(-3425 4650);
DISPLAY 0.702128 (-3425 4650);
PAINT GREEN (-3425 4650);
DISPLAY INVISIBLE (-3425 4650);
FORCEPROP 1 LAST PATH I266
J 2
(-3098 4775);
DISPLAY 0.872340 (-3098 4775);
PAINT GREEN (-3098 4775);
DISPLAY INVISIBLE (-3098 4775);
FORCEADD TAP..6
R 2
(-2950 4525);
FORCEPROP 3 LASTPIN (-3000 4525) SIG_NAME GMI_CPU0_G0_CPU1_G2_TX_DN<11>
J 0
(-2990 4535);
DISPLAY 0.659574 (-2990 4535);
PAINT MONO (-2990 4535);
DISPLAY INVISIBLE (-2990 4535);
FORCEPROP 1 LASTPIN (-3000 4525) BN 11
J 2
(-2948 4533);
DISPLAY 0.489362 (-2948 4533);
PAINT MONO (-2948 4533);
FORCEPROP 2 LAST CDS_LIB standard
J 0
(-2950 4525);
DISPLAY INVISIBLE (-2950 4525);
FORCEPROP 2 LAST BOM_COST IO_SLOT
J 0
(-3450 4625);
DISPLAY 0.829787 (-3450 4625);
DISPLAY INVISIBLE (-3450 4625);
FORCEPROP 2 LAST ROOM RISER1
J 0
(-3450 4575);
DISPLAY 0.829787 (-3450 4575);
PAINT RED (-3450 4575);
DISPLAY INVISIBLE (-3450 4575);
FORCEPROP 1 LAST BODY_TYPE PLUMBING
J 2
(-2950 4475);
DISPLAY 0.702128 (-2950 4475);
PAINT GREEN (-2950 4475);
DISPLAY INVISIBLE (-2950 4475);
FORCEPROP 1 LAST HDL_TAP TRUE
J 2
(-3275 4400);
DISPLAY 0.702128 (-3275 4400);
PAINT GREEN (-3275 4400);
DISPLAY INVISIBLE (-3275 4400);
FORCEPROP 1 LAST PATH I267
J 2
(-2948 4525);
DISPLAY 0.872340 (-2948 4525);
PAINT GREEN (-2948 4525);
DISPLAY INVISIBLE (-2948 4525);
FORCEADD TAP..6
R 2
(-2950 4425);
FORCEPROP 3 LASTPIN (-3000 4425) SIG_NAME GMI_CPU0_G0_CPU1_G2_TX_DN<12>
J 0
(-2990 4435);
DISPLAY 0.659574 (-2990 4435);
PAINT MONO (-2990 4435);
DISPLAY INVISIBLE (-2990 4435);
FORCEPROP 1 LASTPIN (-3000 4425) BN 12
J 2
(-2948 4433);
DISPLAY 0.489362 (-2948 4433);
PAINT MONO (-2948 4433);
FORCEPROP 2 LAST CDS_LIB standard
J 0
(-2950 4425);
DISPLAY INVISIBLE (-2950 4425);
FORCEPROP 2 LAST BOM_COST IO_SLOT
J 0
(-3450 4525);
DISPLAY 0.829787 (-3450 4525);
DISPLAY INVISIBLE (-3450 4525);
FORCEPROP 2 LAST ROOM RISER1
J 0
(-3450 4475);
DISPLAY 0.829787 (-3450 4475);
PAINT RED (-3450 4475);
DISPLAY INVISIBLE (-3450 4475);
FORCEPROP 1 LAST BODY_TYPE PLUMBING
J 2
(-2950 4375);
DISPLAY 0.702128 (-2950 4375);
PAINT GREEN (-2950 4375);
DISPLAY INVISIBLE (-2950 4375);
FORCEPROP 1 LAST HDL_TAP TRUE
J 2
(-3275 4300);
DISPLAY 0.702128 (-3275 4300);
PAINT GREEN (-3275 4300);
DISPLAY INVISIBLE (-3275 4300);
FORCEPROP 1 LAST PATH I268
J 2
(-2948 4425);
DISPLAY 0.872340 (-2948 4425);
PAINT GREEN (-2948 4425);
DISPLAY INVISIBLE (-2948 4425);
FORCEADD TAP..6
R 2
(-3100 4375);
FORCEPROP 3 LASTPIN (-3150 4375) SIG_NAME GMI_CPU0_G0_CPU1_G2_TX_DP<13>
J 0
(-3140 4385);
DISPLAY 0.659574 (-3140 4385);
PAINT MONO (-3140 4385);
DISPLAY INVISIBLE (-3140 4385);
FORCEPROP 1 LASTPIN (-3150 4375) BN 13
J 2
(-3098 4383);
DISPLAY 0.489362 (-3098 4383);
PAINT MONO (-3098 4383);
FORCEPROP 2 LAST BOM_COST IO_SLOT
J 0
(-3600 4475);
DISPLAY 0.829787 (-3600 4475);
DISPLAY INVISIBLE (-3600 4475);
FORCEPROP 2 LAST CDS_LIB standard
J 0
(-3100 4375);
DISPLAY INVISIBLE (-3100 4375);
FORCEPROP 2 LAST ROOM RISER1
J 0
(-3600 4425);
DISPLAY 0.829787 (-3600 4425);
PAINT RED (-3600 4425);
DISPLAY INVISIBLE (-3600 4425);
FORCEPROP 1 LAST BODY_TYPE PLUMBING
J 2
(-3100 4325);
DISPLAY 0.702128 (-3100 4325);
PAINT GREEN (-3100 4325);
DISPLAY INVISIBLE (-3100 4325);
FORCEPROP 1 LAST HDL_TAP TRUE
J 2
(-3425 4250);
DISPLAY 0.702128 (-3425 4250);
PAINT GREEN (-3425 4250);
DISPLAY INVISIBLE (-3425 4250);
FORCEPROP 1 LAST PATH I269
J 2
(-3098 4375);
DISPLAY 0.872340 (-3098 4375);
PAINT GREEN (-3098 4375);
DISPLAY INVISIBLE (-3098 4375);
FORCEADD TAP..6
R 2
(-3100 4475);
FORCEPROP 3 LASTPIN (-3150 4475) SIG_NAME GMI_CPU0_G0_CPU1_G2_TX_DP<12>
J 0
(-3140 4485);
DISPLAY 0.659574 (-3140 4485);
PAINT MONO (-3140 4485);
DISPLAY INVISIBLE (-3140 4485);
FORCEPROP 1 LASTPIN (-3150 4475) BN 12
J 2
(-3098 4483);
DISPLAY 0.489362 (-3098 4483);
PAINT MONO (-3098 4483);
FORCEPROP 2 LAST BOM_COST IO_SLOT
J 0
(-3600 4575);
DISPLAY 0.829787 (-3600 4575);
DISPLAY INVISIBLE (-3600 4575);
FORCEPROP 2 LAST CDS_LIB standard
J 0
(-3100 4475);
DISPLAY INVISIBLE (-3100 4475);
FORCEPROP 2 LAST ROOM RISER1
J 0
(-3600 4525);
DISPLAY 0.829787 (-3600 4525);
PAINT RED (-3600 4525);
DISPLAY INVISIBLE (-3600 4525);
FORCEPROP 1 LAST BODY_TYPE PLUMBING
J 2
(-3100 4425);
DISPLAY 0.702128 (-3100 4425);
PAINT GREEN (-3100 4425);
DISPLAY INVISIBLE (-3100 4425);
FORCEPROP 1 LAST HDL_TAP TRUE
J 2
(-3425 4350);
DISPLAY 0.702128 (-3425 4350);
PAINT GREEN (-3425 4350);
DISPLAY INVISIBLE (-3425 4350);
FORCEPROP 1 LAST PATH I270
J 2
(-3098 4475);
DISPLAY 0.872340 (-3098 4475);
PAINT GREEN (-3098 4475);
DISPLAY INVISIBLE (-3098 4475);
FORCEADD TAP..6
R 2
(-3100 4575);
FORCEPROP 3 LASTPIN (-3150 4575) SIG_NAME GMI_CPU0_G0_CPU1_G2_TX_DP<11>
J 0
(-3140 4585);
DISPLAY 0.659574 (-3140 4585);
PAINT MONO (-3140 4585);
DISPLAY INVISIBLE (-3140 4585);
FORCEPROP 1 LASTPIN (-3150 4575) BN 11
J 2
(-3098 4583);
DISPLAY 0.489362 (-3098 4583);
PAINT MONO (-3098 4583);
FORCEPROP 2 LAST BOM_COST IO_SLOT
J 0
(-3600 4675);
DISPLAY 0.829787 (-3600 4675);
DISPLAY INVISIBLE (-3600 4675);
FORCEPROP 2 LAST CDS_LIB standard
J 0
(-3100 4575);
DISPLAY INVISIBLE (-3100 4575);
FORCEPROP 2 LAST ROOM RISER1
J 0
(-3600 4625);
DISPLAY 0.829787 (-3600 4625);
PAINT RED (-3600 4625);
DISPLAY INVISIBLE (-3600 4625);
FORCEPROP 1 LAST BODY_TYPE PLUMBING
J 2
(-3100 4525);
DISPLAY 0.702128 (-3100 4525);
PAINT GREEN (-3100 4525);
DISPLAY INVISIBLE (-3100 4525);
FORCEPROP 1 LAST HDL_TAP TRUE
J 2
(-3425 4450);
DISPLAY 0.702128 (-3425 4450);
PAINT GREEN (-3425 4450);
DISPLAY INVISIBLE (-3425 4450);
FORCEPROP 1 LAST PATH I271
J 2
(-3098 4575);
DISPLAY 0.872340 (-3098 4575);
PAINT GREEN (-3098 4575);
DISPLAY INVISIBLE (-3098 4575);
FORCEADD TAP..6
R 2
(-2950 4225);
FORCEPROP 3 LASTPIN (-3000 4225) SIG_NAME GMI_CPU0_G0_CPU1_G2_TX_DN<14>
J 0
(-2990 4235);
DISPLAY 0.659574 (-2990 4235);
PAINT MONO (-2990 4235);
DISPLAY INVISIBLE (-2990 4235);
FORCEPROP 1 LASTPIN (-3000 4225) BN 14
J 2
(-2948 4233);
DISPLAY 0.489362 (-2948 4233);
PAINT MONO (-2948 4233);
FORCEPROP 2 LAST BOM_COST IO_SLOT
J 0
(-3450 4325);
DISPLAY 0.829787 (-3450 4325);
DISPLAY INVISIBLE (-3450 4325);
FORCEPROP 2 LAST CDS_LIB standard
J 0
(-2950 4225);
DISPLAY INVISIBLE (-2950 4225);
FORCEPROP 2 LAST ROOM RISER1
J 0
(-3450 4275);
DISPLAY 0.829787 (-3450 4275);
PAINT RED (-3450 4275);
DISPLAY INVISIBLE (-3450 4275);
FORCEPROP 1 LAST BODY_TYPE PLUMBING
J 2
(-2950 4175);
DISPLAY 0.702128 (-2950 4175);
PAINT GREEN (-2950 4175);
DISPLAY INVISIBLE (-2950 4175);
FORCEPROP 1 LAST HDL_TAP TRUE
J 2
(-3275 4100);
DISPLAY 0.702128 (-3275 4100);
PAINT GREEN (-3275 4100);
DISPLAY INVISIBLE (-3275 4100);
FORCEPROP 1 LAST PATH I272
J 2
(-2948 4225);
DISPLAY 0.872340 (-2948 4225);
PAINT GREEN (-2948 4225);
DISPLAY INVISIBLE (-2948 4225);
FORCEADD TAP..6
R 2
(-2950 4125);
FORCEPROP 3 LASTPIN (-3000 4125) SIG_NAME GMI_CPU0_G0_CPU1_G2_TX_DN<15>
J 0
(-2990 4135);
DISPLAY 0.659574 (-2990 4135);
PAINT MONO (-2990 4135);
DISPLAY INVISIBLE (-2990 4135);
FORCEPROP 1 LASTPIN (-3000 4125) BN 15
J 2
(-2948 4133);
DISPLAY 0.489362 (-2948 4133);
PAINT MONO (-2948 4133);
FORCEPROP 2 LAST CDS_LIB standard
J 0
(-2950 4125);
DISPLAY INVISIBLE (-2950 4125);
FORCEPROP 2 LAST BOM_COST IO_SLOT
J 0
(-3450 4225);
DISPLAY 0.829787 (-3450 4225);
DISPLAY INVISIBLE (-3450 4225);
FORCEPROP 2 LAST ROOM RISER1
J 0
(-3450 4175);
DISPLAY 0.829787 (-3450 4175);
PAINT RED (-3450 4175);
DISPLAY INVISIBLE (-3450 4175);
FORCEPROP 1 LAST BODY_TYPE PLUMBING
J 2
(-2950 4075);
DISPLAY 0.702128 (-2950 4075);
PAINT GREEN (-2950 4075);
DISPLAY INVISIBLE (-2950 4075);
FORCEPROP 1 LAST HDL_TAP TRUE
J 2
(-3275 4000);
DISPLAY 0.702128 (-3275 4000);
PAINT GREEN (-3275 4000);
DISPLAY INVISIBLE (-3275 4000);
FORCEPROP 1 LAST PATH I273
J 2
(-2948 4125);
DISPLAY 0.872340 (-2948 4125);
PAINT GREEN (-2948 4125);
DISPLAY INVISIBLE (-2948 4125);
FORCEADD TAP..6
R 2
(-2950 4325);
FORCEPROP 3 LASTPIN (-3000 4325) SIG_NAME GMI_CPU0_G0_CPU1_G2_TX_DN<13>
J 0
(-2990 4335);
DISPLAY 0.659574 (-2990 4335);
PAINT MONO (-2990 4335);
DISPLAY INVISIBLE (-2990 4335);
FORCEPROP 1 LASTPIN (-3000 4325) BN 13
J 2
(-2948 4333);
DISPLAY 0.489362 (-2948 4333);
PAINT MONO (-2948 4333);
FORCEPROP 2 LAST CDS_LIB standard
J 0
(-2950 4325);
DISPLAY INVISIBLE (-2950 4325);
FORCEPROP 2 LAST BOM_COST IO_SLOT
J 0
(-3450 4425);
DISPLAY 0.829787 (-3450 4425);
DISPLAY INVISIBLE (-3450 4425);
FORCEPROP 2 LAST ROOM RISER1
J 0
(-3450 4375);
DISPLAY 0.829787 (-3450 4375);
PAINT RED (-3450 4375);
DISPLAY INVISIBLE (-3450 4375);
FORCEPROP 1 LAST BODY_TYPE PLUMBING
J 2
(-2950 4275);
DISPLAY 0.702128 (-2950 4275);
PAINT GREEN (-2950 4275);
DISPLAY INVISIBLE (-2950 4275);
FORCEPROP 1 LAST HDL_TAP TRUE
J 2
(-3275 4200);
DISPLAY 0.702128 (-3275 4200);
PAINT GREEN (-3275 4200);
DISPLAY INVISIBLE (-3275 4200);
FORCEPROP 1 LAST PATH I274
J 2
(-2948 4325);
DISPLAY 0.872340 (-2948 4325);
PAINT GREEN (-2948 4325);
DISPLAY INVISIBLE (-2948 4325);
FORCEADD TAP..6
R 2
(-3100 4175);
FORCEPROP 3 LASTPIN (-3150 4175) SIG_NAME GMI_CPU0_G0_CPU1_G2_TX_DP<15>
J 0
(-3140 4185);
DISPLAY 0.659574 (-3140 4185);
PAINT MONO (-3140 4185);
DISPLAY INVISIBLE (-3140 4185);
FORCEPROP 1 LASTPIN (-3150 4175) BN 15
J 2
(-3098 4183);
DISPLAY 0.489362 (-3098 4183);
PAINT MONO (-3098 4183);
FORCEPROP 2 LAST BOM_COST IO_SLOT
J 0
(-3600 4275);
DISPLAY 0.829787 (-3600 4275);
DISPLAY INVISIBLE (-3600 4275);
FORCEPROP 2 LAST CDS_LIB standard
J 0
(-3100 4175);
DISPLAY INVISIBLE (-3100 4175);
FORCEPROP 2 LAST ROOM RISER1
J 0
(-3600 4225);
DISPLAY 0.829787 (-3600 4225);
PAINT RED (-3600 4225);
DISPLAY INVISIBLE (-3600 4225);
FORCEPROP 1 LAST BODY_TYPE PLUMBING
J 2
(-3100 4125);
DISPLAY 0.702128 (-3100 4125);
PAINT GREEN (-3100 4125);
DISPLAY INVISIBLE (-3100 4125);
FORCEPROP 1 LAST HDL_TAP TRUE
J 2
(-3425 4050);
DISPLAY 0.702128 (-3425 4050);
PAINT GREEN (-3425 4050);
DISPLAY INVISIBLE (-3425 4050);
FORCEPROP 1 LAST PATH I275
J 2
(-3098 4175);
DISPLAY 0.872340 (-3098 4175);
PAINT GREEN (-3098 4175);
DISPLAY INVISIBLE (-3098 4175);
FORCEADD TAP..6
R 2
(-3100 4275);
FORCEPROP 3 LASTPIN (-3150 4275) SIG_NAME GMI_CPU0_G0_CPU1_G2_TX_DP<14>
J 0
(-3140 4285);
DISPLAY 0.659574 (-3140 4285);
PAINT MONO (-3140 4285);
DISPLAY INVISIBLE (-3140 4285);
FORCEPROP 1 LASTPIN (-3150 4275) BN 14
J 2
(-3098 4283);
DISPLAY 0.489362 (-3098 4283);
PAINT MONO (-3098 4283);
FORCEPROP 2 LAST BOM_COST IO_SLOT
J 0
(-3600 4375);
DISPLAY 0.829787 (-3600 4375);
DISPLAY INVISIBLE (-3600 4375);
FORCEPROP 2 LAST CDS_LIB standard
J 0
(-3100 4275);
DISPLAY INVISIBLE (-3100 4275);
FORCEPROP 2 LAST ROOM RISER1
J 0
(-3600 4325);
DISPLAY 0.829787 (-3600 4325);
PAINT RED (-3600 4325);
DISPLAY INVISIBLE (-3600 4325);
FORCEPROP 1 LAST BODY_TYPE PLUMBING
J 2
(-3100 4225);
DISPLAY 0.702128 (-3100 4225);
PAINT GREEN (-3100 4225);
DISPLAY INVISIBLE (-3100 4225);
FORCEPROP 1 LAST HDL_TAP TRUE
J 2
(-3425 4150);
DISPLAY 0.702128 (-3425 4150);
PAINT GREEN (-3425 4150);
DISPLAY INVISIBLE (-3425 4150);
FORCEPROP 1 LAST PATH I276
J 2
(-3098 4275);
DISPLAY 0.872340 (-3098 4275);
PAINT GREEN (-3098 4275);
DISPLAY INVISIBLE (-3098 4275);
FORCEADD TAP..6
(-6525 5675);
FORCEPROP 3 LASTPIN (-6475 5675) SIG_NAME GMI_CPU1_G2_CPU0_G0_TX_DP<0>
J 0
(-6465 5685);
DISPLAY 0.659574 (-6465 5685);
PAINT MONO (-6465 5685);
DISPLAY INVISIBLE (-6465 5685);
FORCEPROP 1 LASTPIN (-6475 5675) BN 0
J 0
(-6527 5683);
DISPLAY 0.489362 (-6527 5683);
PAINT MONO (-6527 5683);
FORCEPROP 2 LAST CDS_LIB mstr_standard
J 0
(-6525 5675);
DISPLAY INVISIBLE (-6525 5675);
FORCEPROP 1 LAST BODY_TYPE PLUMBING
J 0
(-6525 5625);
DISPLAY 0.574468 (-6525 5625);
PAINT GREEN (-6525 5625);
DISPLAY INVISIBLE (-6525 5625);
FORCEPROP 1 LAST HDL_TAP TRUE
J 0
(-6200 5550);
DISPLAY 0.574468 (-6200 5550);
PAINT GREEN (-6200 5550);
DISPLAY INVISIBLE (-6200 5550);
FORCEPROP 1 LAST PATH I277
J 0
(-6527 5675);
DISPLAY 0.872340 (-6527 5675);
PAINT GREEN (-6527 5675);
DISPLAY INVISIBLE (-6527 5675);
FORCEADD TAP..6
(-6525 5575);
FORCEPROP 3 LASTPIN (-6475 5575) SIG_NAME GMI_CPU1_G2_CPU0_G0_TX_DP<1>
J 0
(-6465 5585);
DISPLAY 0.659574 (-6465 5585);
PAINT MONO (-6465 5585);
DISPLAY INVISIBLE (-6465 5585);
FORCEPROP 1 LASTPIN (-6475 5575) BN 1
J 0
(-6527 5583);
DISPLAY 0.489362 (-6527 5583);
PAINT MONO (-6527 5583);
FORCEPROP 2 LAST CDS_LIB mstr_standard
J 0
(-6525 5575);
DISPLAY INVISIBLE (-6525 5575);
FORCEPROP 1 LAST BODY_TYPE PLUMBING
J 0
(-6525 5525);
DISPLAY 0.574468 (-6525 5525);
PAINT GREEN (-6525 5525);
DISPLAY INVISIBLE (-6525 5525);
FORCEPROP 1 LAST HDL_TAP TRUE
J 0
(-6200 5450);
DISPLAY 0.574468 (-6200 5450);
PAINT GREEN (-6200 5450);
DISPLAY INVISIBLE (-6200 5450);
FORCEPROP 1 LAST PATH I278
J 0
(-6527 5575);
DISPLAY 0.872340 (-6527 5575);
PAINT GREEN (-6527 5575);
DISPLAY INVISIBLE (-6527 5575);
FORCEADD TAP..6
(-6525 5475);
FORCEPROP 3 LASTPIN (-6475 5475) SIG_NAME GMI_CPU1_G2_CPU0_G0_TX_DP<2>
J 0
(-6465 5485);
DISPLAY 0.659574 (-6465 5485);
PAINT MONO (-6465 5485);
DISPLAY INVISIBLE (-6465 5485);
FORCEPROP 1 LASTPIN (-6475 5475) BN 2
J 0
(-6527 5483);
DISPLAY 0.489362 (-6527 5483);
PAINT MONO (-6527 5483);
FORCEPROP 2 LAST CDS_LIB mstr_standard
J 0
(-6525 5475);
DISPLAY INVISIBLE (-6525 5475);
FORCEPROP 1 LAST BODY_TYPE PLUMBING
J 0
(-6525 5425);
DISPLAY 0.574468 (-6525 5425);
PAINT GREEN (-6525 5425);
DISPLAY INVISIBLE (-6525 5425);
FORCEPROP 1 LAST HDL_TAP TRUE
J 0
(-6200 5350);
DISPLAY 0.574468 (-6200 5350);
PAINT GREEN (-6200 5350);
DISPLAY INVISIBLE (-6200 5350);
FORCEPROP 1 LAST PATH I279
J 0
(-6527 5475);
DISPLAY 0.872340 (-6527 5475);
PAINT GREEN (-6527 5475);
DISPLAY INVISIBLE (-6527 5475);
FORCEADD TAP..6
(-6675 5625);
FORCEPROP 3 LASTPIN (-6625 5625) SIG_NAME GMI_CPU1_G2_CPU0_G0_TX_DN<0>
J 0
(-6615 5635);
DISPLAY 0.659574 (-6615 5635);
PAINT MONO (-6615 5635);
DISPLAY INVISIBLE (-6615 5635);
FORCEPROP 1 LASTPIN (-6625 5625) BN 0
J 0
(-6677 5633);
DISPLAY 0.489362 (-6677 5633);
PAINT MONO (-6677 5633);
FORCEPROP 2 LAST CDS_LIB mstr_standard
J 0
(-6675 5625);
DISPLAY INVISIBLE (-6675 5625);
FORCEPROP 1 LAST BODY_TYPE PLUMBING
J 0
(-6675 5575);
DISPLAY 0.574468 (-6675 5575);
PAINT GREEN (-6675 5575);
DISPLAY INVISIBLE (-6675 5575);
FORCEPROP 1 LAST HDL_TAP TRUE
J 0
(-6350 5500);
DISPLAY 0.574468 (-6350 5500);
PAINT GREEN (-6350 5500);
DISPLAY INVISIBLE (-6350 5500);
FORCEPROP 1 LAST PATH I280
J 0
(-6677 5625);
DISPLAY 0.872340 (-6677 5625);
PAINT GREEN (-6677 5625);
DISPLAY INVISIBLE (-6677 5625);
FORCEADD TAP..6
(-6675 5525);
FORCEPROP 3 LASTPIN (-6625 5525) SIG_NAME GMI_CPU1_G2_CPU0_G0_TX_DN<1>
J 0
(-6615 5535);
DISPLAY 0.659574 (-6615 5535);
PAINT MONO (-6615 5535);
DISPLAY INVISIBLE (-6615 5535);
FORCEPROP 1 LASTPIN (-6625 5525) BN 1
J 0
(-6677 5533);
DISPLAY 0.489362 (-6677 5533);
PAINT MONO (-6677 5533);
FORCEPROP 2 LAST CDS_LIB mstr_standard
J 0
(-6675 5525);
DISPLAY INVISIBLE (-6675 5525);
FORCEPROP 1 LAST BODY_TYPE PLUMBING
J 0
(-6675 5475);
DISPLAY 0.574468 (-6675 5475);
PAINT GREEN (-6675 5475);
DISPLAY INVISIBLE (-6675 5475);
FORCEPROP 1 LAST HDL_TAP TRUE
J 0
(-6350 5400);
DISPLAY 0.574468 (-6350 5400);
PAINT GREEN (-6350 5400);
DISPLAY INVISIBLE (-6350 5400);
FORCEPROP 1 LAST PATH I281
J 0
(-6677 5525);
DISPLAY 0.872340 (-6677 5525);
PAINT GREEN (-6677 5525);
DISPLAY INVISIBLE (-6677 5525);
FORCEADD TAP..6
(-6675 5425);
FORCEPROP 3 LASTPIN (-6625 5425) SIG_NAME GMI_CPU1_G2_CPU0_G0_TX_DN<2>
J 0
(-6615 5435);
DISPLAY 0.659574 (-6615 5435);
PAINT MONO (-6615 5435);
DISPLAY INVISIBLE (-6615 5435);
FORCEPROP 1 LASTPIN (-6625 5425) BN 2
J 0
(-6677 5433);
DISPLAY 0.489362 (-6677 5433);
PAINT MONO (-6677 5433);
FORCEPROP 2 LAST CDS_LIB standard
J 0
(-6675 5425);
DISPLAY INVISIBLE (-6675 5425);
FORCEPROP 1 LAST BODY_TYPE PLUMBING
J 0
(-6675 5375);
DISPLAY 0.574468 (-6675 5375);
PAINT GREEN (-6675 5375);
DISPLAY INVISIBLE (-6675 5375);
FORCEPROP 1 LAST HDL_TAP TRUE
J 0
(-6350 5300);
DISPLAY 0.574468 (-6350 5300);
PAINT GREEN (-6350 5300);
DISPLAY INVISIBLE (-6350 5300);
FORCEPROP 1 LAST PATH I282
J 0
(-6677 5425);
DISPLAY 0.872340 (-6677 5425);
PAINT GREEN (-6677 5425);
DISPLAY INVISIBLE (-6677 5425);
FORCEADD TAP..6
(-6525 5275);
FORCEPROP 3 LASTPIN (-6475 5275) SIG_NAME GMI_CPU1_G2_CPU0_G0_TX_DP<4>
J 0
(-6465 5285);
DISPLAY 0.659574 (-6465 5285);
PAINT MONO (-6465 5285);
DISPLAY INVISIBLE (-6465 5285);
FORCEPROP 1 LASTPIN (-6475 5275) BN 4
J 0
(-6527 5283);
DISPLAY 0.489362 (-6527 5283);
PAINT MONO (-6527 5283);
FORCEPROP 2 LAST CDS_LIB standard
J 0
(-6525 5275);
DISPLAY INVISIBLE (-6525 5275);
FORCEPROP 1 LAST BODY_TYPE PLUMBING
J 0
(-6525 5225);
DISPLAY 0.574468 (-6525 5225);
PAINT GREEN (-6525 5225);
DISPLAY INVISIBLE (-6525 5225);
FORCEPROP 1 LAST HDL_TAP TRUE
J 0
(-6200 5150);
DISPLAY 0.574468 (-6200 5150);
PAINT GREEN (-6200 5150);
DISPLAY INVISIBLE (-6200 5150);
FORCEPROP 1 LAST PATH I283
J 0
(-6527 5275);
DISPLAY 0.872340 (-6527 5275);
PAINT GREEN (-6527 5275);
DISPLAY INVISIBLE (-6527 5275);
FORCEADD TAP..6
(-6525 5375);
FORCEPROP 3 LASTPIN (-6475 5375) SIG_NAME GMI_CPU1_G2_CPU0_G0_TX_DP<3>
J 0
(-6465 5385);
DISPLAY 0.659574 (-6465 5385);
PAINT MONO (-6465 5385);
DISPLAY INVISIBLE (-6465 5385);
FORCEPROP 1 LASTPIN (-6475 5375) BN 3
J 0
(-6527 5383);
DISPLAY 0.489362 (-6527 5383);
PAINT MONO (-6527 5383);
FORCEPROP 2 LAST CDS_LIB standard
J 0
(-6525 5375);
DISPLAY INVISIBLE (-6525 5375);
FORCEPROP 1 LAST BODY_TYPE PLUMBING
J 0
(-6525 5325);
DISPLAY 0.574468 (-6525 5325);
PAINT GREEN (-6525 5325);
DISPLAY INVISIBLE (-6525 5325);
FORCEPROP 1 LAST HDL_TAP TRUE
J 0
(-6200 5250);
DISPLAY 0.574468 (-6200 5250);
PAINT GREEN (-6200 5250);
DISPLAY INVISIBLE (-6200 5250);
FORCEPROP 1 LAST PATH I284
J 0
(-6527 5375);
DISPLAY 0.872340 (-6527 5375);
PAINT GREEN (-6527 5375);
DISPLAY INVISIBLE (-6527 5375);
FORCEADD TAP..6
(-6525 5175);
FORCEPROP 3 LASTPIN (-6475 5175) SIG_NAME GMI_CPU1_G2_CPU0_G0_TX_DP<5>
J 0
(-6465 5185);
DISPLAY 0.659574 (-6465 5185);
PAINT MONO (-6465 5185);
DISPLAY INVISIBLE (-6465 5185);
FORCEPROP 1 LASTPIN (-6475 5175) BN 5
J 0
(-6527 5183);
DISPLAY 0.489362 (-6527 5183);
PAINT MONO (-6527 5183);
FORCEPROP 2 LAST CDS_LIB standard
J 0
(-6525 5175);
DISPLAY INVISIBLE (-6525 5175);
FORCEPROP 1 LAST BODY_TYPE PLUMBING
J 0
(-6525 5125);
DISPLAY 0.574468 (-6525 5125);
PAINT GREEN (-6525 5125);
DISPLAY INVISIBLE (-6525 5125);
FORCEPROP 1 LAST HDL_TAP TRUE
J 0
(-6200 5050);
DISPLAY 0.574468 (-6200 5050);
PAINT GREEN (-6200 5050);
DISPLAY INVISIBLE (-6200 5050);
FORCEPROP 1 LAST PATH I285
J 0
(-6527 5175);
DISPLAY 0.872340 (-6527 5175);
PAINT GREEN (-6527 5175);
DISPLAY INVISIBLE (-6527 5175);
FORCEADD TAP..6
(-6675 5325);
FORCEPROP 3 LASTPIN (-6625 5325) SIG_NAME GMI_CPU1_G2_CPU0_G0_TX_DN<3>
J 0
(-6615 5335);
DISPLAY 0.659574 (-6615 5335);
PAINT MONO (-6615 5335);
DISPLAY INVISIBLE (-6615 5335);
FORCEPROP 1 LASTPIN (-6625 5325) BN 3
J 0
(-6677 5333);
DISPLAY 0.489362 (-6677 5333);
PAINT MONO (-6677 5333);
FORCEPROP 2 LAST CDS_LIB standard
J 0
(-6675 5325);
DISPLAY INVISIBLE (-6675 5325);
FORCEPROP 1 LAST BODY_TYPE PLUMBING
J 0
(-6675 5275);
DISPLAY 0.574468 (-6675 5275);
PAINT GREEN (-6675 5275);
DISPLAY INVISIBLE (-6675 5275);
FORCEPROP 1 LAST HDL_TAP TRUE
J 0
(-6350 5200);
DISPLAY 0.574468 (-6350 5200);
PAINT GREEN (-6350 5200);
DISPLAY INVISIBLE (-6350 5200);
FORCEPROP 1 LAST PATH I286
J 0
(-6677 5325);
DISPLAY 0.872340 (-6677 5325);
PAINT GREEN (-6677 5325);
DISPLAY INVISIBLE (-6677 5325);
FORCEADD TAP..6
(-6675 5225);
FORCEPROP 3 LASTPIN (-6625 5225) SIG_NAME GMI_CPU1_G2_CPU0_G0_TX_DN<4>
J 0
(-6615 5235);
DISPLAY 0.659574 (-6615 5235);
PAINT MONO (-6615 5235);
DISPLAY INVISIBLE (-6615 5235);
FORCEPROP 1 LASTPIN (-6625 5225) BN 4
J 0
(-6677 5233);
DISPLAY 0.489362 (-6677 5233);
PAINT MONO (-6677 5233);
FORCEPROP 2 LAST CDS_LIB standard
J 0
(-6675 5225);
DISPLAY INVISIBLE (-6675 5225);
FORCEPROP 1 LAST BODY_TYPE PLUMBING
J 0
(-6675 5175);
DISPLAY 0.574468 (-6675 5175);
PAINT GREEN (-6675 5175);
DISPLAY INVISIBLE (-6675 5175);
FORCEPROP 1 LAST HDL_TAP TRUE
J 0
(-6350 5100);
DISPLAY 0.574468 (-6350 5100);
PAINT GREEN (-6350 5100);
DISPLAY INVISIBLE (-6350 5100);
FORCEPROP 1 LAST PATH I287
J 0
(-6677 5225);
DISPLAY 0.872340 (-6677 5225);
PAINT GREEN (-6677 5225);
DISPLAY INVISIBLE (-6677 5225);
FORCEADD TAP..6
(-6675 5125);
FORCEPROP 3 LASTPIN (-6625 5125) SIG_NAME GMI_CPU1_G2_CPU0_G0_TX_DN<5>
J 0
(-6615 5135);
DISPLAY 0.659574 (-6615 5135);
PAINT MONO (-6615 5135);
DISPLAY INVISIBLE (-6615 5135);
FORCEPROP 1 LASTPIN (-6625 5125) BN 5
J 0
(-6677 5133);
DISPLAY 0.489362 (-6677 5133);
PAINT MONO (-6677 5133);
FORCEPROP 2 LAST CDS_LIB standard
J 0
(-6675 5125);
DISPLAY INVISIBLE (-6675 5125);
FORCEPROP 1 LAST BODY_TYPE PLUMBING
J 0
(-6675 5075);
DISPLAY 0.574468 (-6675 5075);
PAINT GREEN (-6675 5075);
DISPLAY INVISIBLE (-6675 5075);
FORCEPROP 1 LAST HDL_TAP TRUE
J 0
(-6350 5000);
DISPLAY 0.574468 (-6350 5000);
PAINT GREEN (-6350 5000);
DISPLAY INVISIBLE (-6350 5000);
FORCEPROP 1 LAST PATH I288
J 0
(-6677 5125);
DISPLAY 0.872340 (-6677 5125);
PAINT GREEN (-6677 5125);
DISPLAY INVISIBLE (-6677 5125);
FORCEADD TAP..6
(-6525 5075);
FORCEPROP 3 LASTPIN (-6475 5075) SIG_NAME GMI_CPU1_G2_CPU0_G0_TX_DP<6>
J 0
(-6465 5085);
DISPLAY 0.659574 (-6465 5085);
PAINT MONO (-6465 5085);
DISPLAY INVISIBLE (-6465 5085);
FORCEPROP 1 LASTPIN (-6475 5075) BN 6
J 0
(-6527 5083);
DISPLAY 0.489362 (-6527 5083);
PAINT MONO (-6527 5083);
FORCEPROP 2 LAST CDS_LIB standard
J 0
(-6525 5075);
DISPLAY INVISIBLE (-6525 5075);
FORCEPROP 1 LAST BODY_TYPE PLUMBING
J 0
(-6525 5025);
DISPLAY 0.574468 (-6525 5025);
PAINT GREEN (-6525 5025);
DISPLAY INVISIBLE (-6525 5025);
FORCEPROP 1 LAST HDL_TAP TRUE
J 0
(-6200 4950);
DISPLAY 0.574468 (-6200 4950);
PAINT GREEN (-6200 4950);
DISPLAY INVISIBLE (-6200 4950);
FORCEPROP 1 LAST PATH I289
J 0
(-6527 5075);
DISPLAY 0.872340 (-6527 5075);
PAINT GREEN (-6527 5075);
DISPLAY INVISIBLE (-6527 5075);
FORCEADD TAP..6
(-6525 4975);
FORCEPROP 3 LASTPIN (-6475 4975) SIG_NAME GMI_CPU1_G2_CPU0_G0_TX_DP<7>
J 0
(-6465 4985);
DISPLAY 0.659574 (-6465 4985);
PAINT MONO (-6465 4985);
DISPLAY INVISIBLE (-6465 4985);
FORCEPROP 1 LASTPIN (-6475 4975) BN 7
J 0
(-6527 4983);
DISPLAY 0.489362 (-6527 4983);
PAINT MONO (-6527 4983);
FORCEPROP 2 LAST CDS_LIB standard
J 0
(-6525 4975);
DISPLAY INVISIBLE (-6525 4975);
FORCEPROP 1 LAST BODY_TYPE PLUMBING
J 0
(-6525 4925);
DISPLAY 0.574468 (-6525 4925);
PAINT GREEN (-6525 4925);
DISPLAY INVISIBLE (-6525 4925);
FORCEPROP 1 LAST HDL_TAP TRUE
J 0
(-6200 4850);
DISPLAY 0.574468 (-6200 4850);
PAINT GREEN (-6200 4850);
DISPLAY INVISIBLE (-6200 4850);
FORCEPROP 1 LAST PATH I290
J 0
(-6527 4975);
DISPLAY 0.872340 (-6527 4975);
PAINT GREEN (-6527 4975);
DISPLAY INVISIBLE (-6527 4975);
FORCEADD TAP..6
(-6525 4875);
FORCEPROP 3 LASTPIN (-6475 4875) SIG_NAME GMI_CPU1_G2_CPU0_G0_TX_DP<8>
J 0
(-6465 4885);
DISPLAY 0.659574 (-6465 4885);
PAINT MONO (-6465 4885);
DISPLAY INVISIBLE (-6465 4885);
FORCEPROP 1 LASTPIN (-6475 4875) BN 8
J 0
(-6527 4883);
DISPLAY 0.489362 (-6527 4883);
PAINT MONO (-6527 4883);
FORCEPROP 2 LAST CDS_LIB standard
J 0
(-6525 4875);
DISPLAY INVISIBLE (-6525 4875);
FORCEPROP 1 LAST BODY_TYPE PLUMBING
J 0
(-6525 4825);
DISPLAY 0.574468 (-6525 4825);
PAINT GREEN (-6525 4825);
DISPLAY INVISIBLE (-6525 4825);
FORCEPROP 1 LAST HDL_TAP TRUE
J 0
(-6200 4750);
DISPLAY 0.574468 (-6200 4750);
PAINT GREEN (-6200 4750);
DISPLAY INVISIBLE (-6200 4750);
FORCEPROP 1 LAST PATH I291
J 0
(-6527 4875);
DISPLAY 0.872340 (-6527 4875);
PAINT GREEN (-6527 4875);
DISPLAY INVISIBLE (-6527 4875);
FORCEADD TAP..6
(-6675 5025);
FORCEPROP 3 LASTPIN (-6625 5025) SIG_NAME GMI_CPU1_G2_CPU0_G0_TX_DN<6>
J 0
(-6615 5035);
DISPLAY 0.659574 (-6615 5035);
PAINT MONO (-6615 5035);
DISPLAY INVISIBLE (-6615 5035);
FORCEPROP 1 LASTPIN (-6625 5025) BN 6
J 0
(-6677 5033);
DISPLAY 0.489362 (-6677 5033);
PAINT MONO (-6677 5033);
FORCEPROP 2 LAST CDS_LIB standard
J 0
(-6675 5025);
DISPLAY INVISIBLE (-6675 5025);
FORCEPROP 1 LAST BODY_TYPE PLUMBING
J 0
(-6675 4975);
DISPLAY 0.574468 (-6675 4975);
PAINT GREEN (-6675 4975);
DISPLAY INVISIBLE (-6675 4975);
FORCEPROP 1 LAST HDL_TAP TRUE
J 0
(-6350 4900);
DISPLAY 0.574468 (-6350 4900);
PAINT GREEN (-6350 4900);
DISPLAY INVISIBLE (-6350 4900);
FORCEPROP 1 LAST PATH I292
J 0
(-6677 5025);
DISPLAY 0.872340 (-6677 5025);
PAINT GREEN (-6677 5025);
DISPLAY INVISIBLE (-6677 5025);
FORCEADD TAP..6
(-6675 4925);
FORCEPROP 3 LASTPIN (-6625 4925) SIG_NAME GMI_CPU1_G2_CPU0_G0_TX_DN<7>
J 0
(-6615 4935);
DISPLAY 0.659574 (-6615 4935);
PAINT MONO (-6615 4935);
DISPLAY INVISIBLE (-6615 4935);
FORCEPROP 1 LASTPIN (-6625 4925) BN 7
J 0
(-6677 4933);
DISPLAY 0.489362 (-6677 4933);
PAINT MONO (-6677 4933);
FORCEPROP 2 LAST CDS_LIB standard
J 0
(-6675 4925);
DISPLAY INVISIBLE (-6675 4925);
FORCEPROP 1 LAST BODY_TYPE PLUMBING
J 0
(-6675 4875);
DISPLAY 0.574468 (-6675 4875);
PAINT GREEN (-6675 4875);
DISPLAY INVISIBLE (-6675 4875);
FORCEPROP 1 LAST HDL_TAP TRUE
J 0
(-6350 4800);
DISPLAY 0.574468 (-6350 4800);
PAINT GREEN (-6350 4800);
DISPLAY INVISIBLE (-6350 4800);
FORCEPROP 1 LAST PATH I293
J 0
(-6677 4925);
DISPLAY 0.872340 (-6677 4925);
PAINT GREEN (-6677 4925);
DISPLAY INVISIBLE (-6677 4925);
FORCEADD TAP..6
(-6525 4775);
FORCEPROP 3 LASTPIN (-6475 4775) SIG_NAME GMI_CPU1_G2_CPU0_G0_TX_DP<9>
J 0
(-6465 4785);
DISPLAY 0.659574 (-6465 4785);
PAINT MONO (-6465 4785);
DISPLAY INVISIBLE (-6465 4785);
FORCEPROP 1 LASTPIN (-6475 4775) BN 9
J 0
(-6527 4783);
DISPLAY 0.489362 (-6527 4783);
PAINT MONO (-6527 4783);
FORCEPROP 2 LAST CDS_LIB standard
J 0
(-6525 4775);
DISPLAY INVISIBLE (-6525 4775);
FORCEPROP 1 LAST BODY_TYPE PLUMBING
J 0
(-6525 4725);
DISPLAY 0.574468 (-6525 4725);
PAINT GREEN (-6525 4725);
DISPLAY INVISIBLE (-6525 4725);
FORCEPROP 1 LAST HDL_TAP TRUE
J 0
(-6200 4650);
DISPLAY 0.574468 (-6200 4650);
PAINT GREEN (-6200 4650);
DISPLAY INVISIBLE (-6200 4650);
FORCEPROP 1 LAST PATH I294
J 0
(-6527 4775);
DISPLAY 0.872340 (-6527 4775);
PAINT GREEN (-6527 4775);
DISPLAY INVISIBLE (-6527 4775);
FORCEADD TAP..6
(-6525 4675);
FORCEPROP 3 LASTPIN (-6475 4675) SIG_NAME GMI_CPU1_G2_CPU0_G0_TX_DP<10>
J 0
(-6465 4685);
DISPLAY 0.659574 (-6465 4685);
PAINT MONO (-6465 4685);
DISPLAY INVISIBLE (-6465 4685);
FORCEPROP 1 LASTPIN (-6475 4675) BN 10
J 0
(-6527 4683);
DISPLAY 0.489362 (-6527 4683);
PAINT MONO (-6527 4683);
FORCEPROP 2 LAST CDS_LIB standard
J 0
(-6525 4675);
DISPLAY INVISIBLE (-6525 4675);
FORCEPROP 1 LAST BODY_TYPE PLUMBING
J 0
(-6525 4625);
DISPLAY 0.574468 (-6525 4625);
PAINT GREEN (-6525 4625);
DISPLAY INVISIBLE (-6525 4625);
FORCEPROP 1 LAST HDL_TAP TRUE
J 0
(-6200 4550);
DISPLAY 0.574468 (-6200 4550);
PAINT GREEN (-6200 4550);
DISPLAY INVISIBLE (-6200 4550);
FORCEPROP 1 LAST PATH I295
J 0
(-6527 4675);
DISPLAY 0.872340 (-6527 4675);
PAINT GREEN (-6527 4675);
DISPLAY INVISIBLE (-6527 4675);
FORCEADD TAP..6
(-6675 4825);
FORCEPROP 3 LASTPIN (-6625 4825) SIG_NAME GMI_CPU1_G2_CPU0_G0_TX_DN<8>
J 0
(-6615 4835);
DISPLAY 0.659574 (-6615 4835);
PAINT MONO (-6615 4835);
DISPLAY INVISIBLE (-6615 4835);
FORCEPROP 1 LASTPIN (-6625 4825) BN 8
J 0
(-6677 4833);
DISPLAY 0.489362 (-6677 4833);
PAINT MONO (-6677 4833);
FORCEPROP 2 LAST CDS_LIB standard
J 0
(-6675 4825);
DISPLAY INVISIBLE (-6675 4825);
FORCEPROP 1 LAST BODY_TYPE PLUMBING
J 0
(-6675 4775);
DISPLAY 0.574468 (-6675 4775);
PAINT GREEN (-6675 4775);
DISPLAY INVISIBLE (-6675 4775);
FORCEPROP 1 LAST HDL_TAP TRUE
J 0
(-6350 4700);
DISPLAY 0.574468 (-6350 4700);
PAINT GREEN (-6350 4700);
DISPLAY INVISIBLE (-6350 4700);
FORCEPROP 1 LAST PATH I296
J 0
(-6677 4825);
DISPLAY 0.872340 (-6677 4825);
PAINT GREEN (-6677 4825);
DISPLAY INVISIBLE (-6677 4825);
FORCEADD TAP..6
(-6675 4725);
FORCEPROP 3 LASTPIN (-6625 4725) SIG_NAME GMI_CPU1_G2_CPU0_G0_TX_DN<9>
J 0
(-6615 4735);
DISPLAY 0.659574 (-6615 4735);
PAINT MONO (-6615 4735);
DISPLAY INVISIBLE (-6615 4735);
FORCEPROP 1 LASTPIN (-6625 4725) BN 9
J 0
(-6677 4733);
DISPLAY 0.489362 (-6677 4733);
PAINT MONO (-6677 4733);
FORCEPROP 2 LAST CDS_LIB standard
J 0
(-6675 4725);
DISPLAY INVISIBLE (-6675 4725);
FORCEPROP 1 LAST BODY_TYPE PLUMBING
J 0
(-6675 4675);
DISPLAY 0.574468 (-6675 4675);
PAINT GREEN (-6675 4675);
DISPLAY INVISIBLE (-6675 4675);
FORCEPROP 1 LAST HDL_TAP TRUE
J 0
(-6350 4600);
DISPLAY 0.574468 (-6350 4600);
PAINT GREEN (-6350 4600);
DISPLAY INVISIBLE (-6350 4600);
FORCEPROP 1 LAST PATH I297
J 0
(-6677 4725);
DISPLAY 0.872340 (-6677 4725);
PAINT GREEN (-6677 4725);
DISPLAY INVISIBLE (-6677 4725);
FORCEADD TAP..6
(-6675 4625);
FORCEPROP 3 LASTPIN (-6625 4625) SIG_NAME GMI_CPU1_G2_CPU0_G0_TX_DN<10>
J 0
(-6615 4635);
DISPLAY 0.659574 (-6615 4635);
PAINT MONO (-6615 4635);
DISPLAY INVISIBLE (-6615 4635);
FORCEPROP 1 LASTPIN (-6625 4625) BN 10
J 0
(-6677 4633);
DISPLAY 0.489362 (-6677 4633);
PAINT MONO (-6677 4633);
FORCEPROP 2 LAST CDS_LIB standard
J 0
(-6675 4625);
DISPLAY INVISIBLE (-6675 4625);
FORCEPROP 1 LAST BODY_TYPE PLUMBING
J 0
(-6675 4575);
DISPLAY 0.574468 (-6675 4575);
PAINT GREEN (-6675 4575);
DISPLAY INVISIBLE (-6675 4575);
FORCEPROP 1 LAST HDL_TAP TRUE
J 0
(-6350 4500);
DISPLAY 0.574468 (-6350 4500);
PAINT GREEN (-6350 4500);
DISPLAY INVISIBLE (-6350 4500);
FORCEPROP 1 LAST PATH I298
J 0
(-6677 4625);
DISPLAY 0.872340 (-6677 4625);
PAINT GREEN (-6677 4625);
DISPLAY INVISIBLE (-6677 4625);
FORCEADD TAP..6
(-6525 4575);
FORCEPROP 3 LASTPIN (-6475 4575) SIG_NAME GMI_CPU1_G2_CPU0_G0_TX_DP<11>
J 0
(-6465 4585);
DISPLAY 0.659574 (-6465 4585);
PAINT MONO (-6465 4585);
DISPLAY INVISIBLE (-6465 4585);
FORCEPROP 1 LASTPIN (-6475 4575) BN 11
J 0
(-6527 4583);
DISPLAY 0.489362 (-6527 4583);
PAINT MONO (-6527 4583);
FORCEPROP 2 LAST CDS_LIB standard
J 0
(-6525 4575);
DISPLAY INVISIBLE (-6525 4575);
FORCEPROP 1 LAST BODY_TYPE PLUMBING
J 0
(-6525 4525);
DISPLAY 0.574468 (-6525 4525);
PAINT GREEN (-6525 4525);
DISPLAY INVISIBLE (-6525 4525);
FORCEPROP 1 LAST HDL_TAP TRUE
J 0
(-6200 4450);
DISPLAY 0.574468 (-6200 4450);
PAINT GREEN (-6200 4450);
DISPLAY INVISIBLE (-6200 4450);
FORCEPROP 1 LAST PATH I299
J 0
(-6527 4575);
DISPLAY 0.872340 (-6527 4575);
PAINT GREEN (-6527 4575);
DISPLAY INVISIBLE (-6527 4575);
FORCEADD TAP..6
(-6525 4475);
FORCEPROP 3 LASTPIN (-6475 4475) SIG_NAME GMI_CPU1_G2_CPU0_G0_TX_DP<12>
J 0
(-6465 4485);
DISPLAY 0.659574 (-6465 4485);
PAINT MONO (-6465 4485);
DISPLAY INVISIBLE (-6465 4485);
FORCEPROP 1 LASTPIN (-6475 4475) BN 12
J 0
(-6527 4483);
DISPLAY 0.489362 (-6527 4483);
PAINT MONO (-6527 4483);
FORCEPROP 2 LAST CDS_LIB standard
J 0
(-6525 4475);
DISPLAY INVISIBLE (-6525 4475);
FORCEPROP 1 LAST BODY_TYPE PLUMBING
J 0
(-6525 4425);
DISPLAY 0.574468 (-6525 4425);
PAINT GREEN (-6525 4425);
DISPLAY INVISIBLE (-6525 4425);
FORCEPROP 1 LAST HDL_TAP TRUE
J 0
(-6200 4350);
DISPLAY 0.574468 (-6200 4350);
PAINT GREEN (-6200 4350);
DISPLAY INVISIBLE (-6200 4350);
FORCEPROP 1 LAST PATH I300
J 0
(-6527 4475);
DISPLAY 0.872340 (-6527 4475);
PAINT GREEN (-6527 4475);
DISPLAY INVISIBLE (-6527 4475);
FORCEADD TAP..6
(-6525 4375);
FORCEPROP 3 LASTPIN (-6475 4375) SIG_NAME GMI_CPU1_G2_CPU0_G0_TX_DP<13>
J 0
(-6465 4385);
DISPLAY 0.659574 (-6465 4385);
PAINT MONO (-6465 4385);
DISPLAY INVISIBLE (-6465 4385);
FORCEPROP 1 LASTPIN (-6475 4375) BN 13
J 0
(-6527 4383);
DISPLAY 0.489362 (-6527 4383);
PAINT MONO (-6527 4383);
FORCEPROP 2 LAST CDS_LIB standard
J 0
(-6525 4375);
DISPLAY INVISIBLE (-6525 4375);
FORCEPROP 1 LAST BODY_TYPE PLUMBING
J 0
(-6525 4325);
DISPLAY 0.574468 (-6525 4325);
PAINT GREEN (-6525 4325);
DISPLAY INVISIBLE (-6525 4325);
FORCEPROP 1 LAST HDL_TAP TRUE
J 0
(-6200 4250);
DISPLAY 0.574468 (-6200 4250);
PAINT GREEN (-6200 4250);
DISPLAY INVISIBLE (-6200 4250);
FORCEPROP 1 LAST PATH I301
J 0
(-6527 4375);
DISPLAY 0.872340 (-6527 4375);
PAINT GREEN (-6527 4375);
DISPLAY INVISIBLE (-6527 4375);
FORCEADD TAP..6
(-6675 4525);
FORCEPROP 3 LASTPIN (-6625 4525) SIG_NAME GMI_CPU1_G2_CPU0_G0_TX_DN<11>
J 0
(-6615 4535);
DISPLAY 0.659574 (-6615 4535);
PAINT MONO (-6615 4535);
DISPLAY INVISIBLE (-6615 4535);
FORCEPROP 1 LASTPIN (-6625 4525) BN 11
J 0
(-6677 4533);
DISPLAY 0.489362 (-6677 4533);
PAINT MONO (-6677 4533);
FORCEPROP 2 LAST CDS_LIB standard
J 0
(-6675 4525);
DISPLAY INVISIBLE (-6675 4525);
FORCEPROP 1 LAST BODY_TYPE PLUMBING
J 0
(-6675 4475);
DISPLAY 0.574468 (-6675 4475);
PAINT GREEN (-6675 4475);
DISPLAY INVISIBLE (-6675 4475);
FORCEPROP 1 LAST HDL_TAP TRUE
J 0
(-6350 4400);
DISPLAY 0.574468 (-6350 4400);
PAINT GREEN (-6350 4400);
DISPLAY INVISIBLE (-6350 4400);
FORCEPROP 1 LAST PATH I302
J 0
(-6677 4525);
DISPLAY 0.872340 (-6677 4525);
PAINT GREEN (-6677 4525);
DISPLAY INVISIBLE (-6677 4525);
FORCEADD TAP..6
(-6675 4425);
FORCEPROP 3 LASTPIN (-6625 4425) SIG_NAME GMI_CPU1_G2_CPU0_G0_TX_DN<12>
J 0
(-6615 4435);
DISPLAY 0.659574 (-6615 4435);
PAINT MONO (-6615 4435);
DISPLAY INVISIBLE (-6615 4435);
FORCEPROP 1 LASTPIN (-6625 4425) BN 12
J 0
(-6677 4433);
DISPLAY 0.489362 (-6677 4433);
PAINT MONO (-6677 4433);
FORCEPROP 2 LAST CDS_LIB standard
J 0
(-6675 4425);
DISPLAY INVISIBLE (-6675 4425);
FORCEPROP 1 LAST BODY_TYPE PLUMBING
J 0
(-6675 4375);
DISPLAY 0.574468 (-6675 4375);
PAINT GREEN (-6675 4375);
DISPLAY INVISIBLE (-6675 4375);
FORCEPROP 1 LAST HDL_TAP TRUE
J 0
(-6350 4300);
DISPLAY 0.574468 (-6350 4300);
PAINT GREEN (-6350 4300);
DISPLAY INVISIBLE (-6350 4300);
FORCEPROP 1 LAST PATH I303
J 0
(-6677 4425);
DISPLAY 0.872340 (-6677 4425);
PAINT GREEN (-6677 4425);
DISPLAY INVISIBLE (-6677 4425);
FORCEADD TAP..6
(-6525 4275);
FORCEPROP 3 LASTPIN (-6475 4275) SIG_NAME GMI_CPU1_G2_CPU0_G0_TX_DP<14>
J 0
(-6465 4285);
DISPLAY 0.659574 (-6465 4285);
PAINT MONO (-6465 4285);
DISPLAY INVISIBLE (-6465 4285);
FORCEPROP 1 LASTPIN (-6475 4275) BN 14
J 0
(-6527 4283);
DISPLAY 0.489362 (-6527 4283);
PAINT MONO (-6527 4283);
FORCEPROP 2 LAST CDS_LIB standard
J 0
(-6525 4275);
DISPLAY INVISIBLE (-6525 4275);
FORCEPROP 1 LAST BODY_TYPE PLUMBING
J 0
(-6525 4225);
DISPLAY 0.574468 (-6525 4225);
PAINT GREEN (-6525 4225);
DISPLAY INVISIBLE (-6525 4225);
FORCEPROP 1 LAST HDL_TAP TRUE
J 0
(-6200 4150);
DISPLAY 0.574468 (-6200 4150);
PAINT GREEN (-6200 4150);
DISPLAY INVISIBLE (-6200 4150);
FORCEPROP 1 LAST PATH I304
J 0
(-6527 4275);
DISPLAY 0.872340 (-6527 4275);
PAINT GREEN (-6527 4275);
DISPLAY INVISIBLE (-6527 4275);
FORCEADD TAP..6
(-6525 4175);
FORCEPROP 3 LASTPIN (-6475 4175) SIG_NAME GMI_CPU1_G2_CPU0_G0_TX_DP<15>
J 0
(-6465 4185);
DISPLAY 0.659574 (-6465 4185);
PAINT MONO (-6465 4185);
DISPLAY INVISIBLE (-6465 4185);
FORCEPROP 1 LASTPIN (-6475 4175) BN 15
J 0
(-6527 4183);
DISPLAY 0.489362 (-6527 4183);
PAINT MONO (-6527 4183);
FORCEPROP 2 LAST CDS_LIB standard
J 0
(-6525 4175);
DISPLAY INVISIBLE (-6525 4175);
FORCEPROP 1 LAST BODY_TYPE PLUMBING
J 0
(-6525 4125);
DISPLAY 0.574468 (-6525 4125);
PAINT GREEN (-6525 4125);
DISPLAY INVISIBLE (-6525 4125);
FORCEPROP 1 LAST HDL_TAP TRUE
J 0
(-6200 4050);
DISPLAY 0.574468 (-6200 4050);
PAINT GREEN (-6200 4050);
DISPLAY INVISIBLE (-6200 4050);
FORCEPROP 1 LAST PATH I305
J 0
(-6527 4175);
DISPLAY 0.872340 (-6527 4175);
PAINT GREEN (-6527 4175);
DISPLAY INVISIBLE (-6527 4175);
FORCEADD TAP..6
(-6675 4325);
FORCEPROP 3 LASTPIN (-6625 4325) SIG_NAME GMI_CPU1_G2_CPU0_G0_TX_DN<13>
J 0
(-6615 4335);
DISPLAY 0.659574 (-6615 4335);
PAINT MONO (-6615 4335);
DISPLAY INVISIBLE (-6615 4335);
FORCEPROP 1 LASTPIN (-6625 4325) BN 13
J 0
(-6677 4333);
DISPLAY 0.489362 (-6677 4333);
PAINT MONO (-6677 4333);
FORCEPROP 2 LAST CDS_LIB standard
J 0
(-6675 4325);
DISPLAY INVISIBLE (-6675 4325);
FORCEPROP 1 LAST BODY_TYPE PLUMBING
J 0
(-6675 4275);
DISPLAY 0.574468 (-6675 4275);
PAINT GREEN (-6675 4275);
DISPLAY INVISIBLE (-6675 4275);
FORCEPROP 1 LAST HDL_TAP TRUE
J 0
(-6350 4200);
DISPLAY 0.574468 (-6350 4200);
PAINT GREEN (-6350 4200);
DISPLAY INVISIBLE (-6350 4200);
FORCEPROP 1 LAST PATH I306
J 0
(-6677 4325);
DISPLAY 0.872340 (-6677 4325);
PAINT GREEN (-6677 4325);
DISPLAY INVISIBLE (-6677 4325);
FORCEADD TAP..6
(-6675 4225);
FORCEPROP 3 LASTPIN (-6625 4225) SIG_NAME GMI_CPU1_G2_CPU0_G0_TX_DN<14>
J 0
(-6615 4235);
DISPLAY 0.659574 (-6615 4235);
PAINT MONO (-6615 4235);
DISPLAY INVISIBLE (-6615 4235);
FORCEPROP 1 LASTPIN (-6625 4225) BN 14
J 0
(-6677 4233);
DISPLAY 0.489362 (-6677 4233);
PAINT MONO (-6677 4233);
FORCEPROP 2 LAST CDS_LIB standard
J 0
(-6675 4225);
DISPLAY INVISIBLE (-6675 4225);
FORCEPROP 1 LAST BODY_TYPE PLUMBING
J 0
(-6675 4175);
DISPLAY 0.574468 (-6675 4175);
PAINT GREEN (-6675 4175);
DISPLAY INVISIBLE (-6675 4175);
FORCEPROP 1 LAST HDL_TAP TRUE
J 0
(-6350 4100);
DISPLAY 0.574468 (-6350 4100);
PAINT GREEN (-6350 4100);
DISPLAY INVISIBLE (-6350 4100);
FORCEPROP 1 LAST PATH I307
J 0
(-6677 4225);
DISPLAY 0.872340 (-6677 4225);
PAINT GREEN (-6677 4225);
DISPLAY INVISIBLE (-6677 4225);
FORCEADD TAP..6
(-6675 4125);
FORCEPROP 3 LASTPIN (-6625 4125) SIG_NAME GMI_CPU1_G2_CPU0_G0_TX_DN<15>
J 0
(-6615 4135);
DISPLAY 0.659574 (-6615 4135);
PAINT MONO (-6615 4135);
DISPLAY INVISIBLE (-6615 4135);
FORCEPROP 1 LASTPIN (-6625 4125) BN 15
J 0
(-6677 4133);
DISPLAY 0.489362 (-6677 4133);
PAINT MONO (-6677 4133);
FORCEPROP 2 LAST CDS_LIB standard
J 0
(-6675 4125);
DISPLAY INVISIBLE (-6675 4125);
FORCEPROP 1 LAST BODY_TYPE PLUMBING
J 0
(-6675 4075);
DISPLAY 0.574468 (-6675 4075);
PAINT GREEN (-6675 4075);
DISPLAY INVISIBLE (-6675 4075);
FORCEPROP 1 LAST HDL_TAP TRUE
J 0
(-6350 4000);
DISPLAY 0.574468 (-6350 4000);
PAINT GREEN (-6350 4000);
DISPLAY INVISIBLE (-6350 4000);
FORCEPROP 1 LAST PATH I308
J 0
(-6677 4125);
DISPLAY 0.872340 (-6677 4125);
PAINT GREEN (-6677 4125);
DISPLAY INVISIBLE (-6677 4125);
FORCEADD OFFPAGE..1
(-7775 5900);
FORCEPROP 2 LAST $XR0 50 
J 0
(-8026 5900);
DISPLAY 0.638298 (-8026 5900);
PAINT MONO (-8026 5900);
FORCEPROP 2 LAST CDS_LIB standard
J 0
(-7775 5900);
DISPLAY INVISIBLE (-7775 5900);
FORCEPROP 1 LAST OFFPAGE TRUE
J 0
(-7450 5775);
DISPLAY 0.872340 (-7450 5775);
PAINT GREEN (-7450 5775);
DISPLAY INVISIBLE (-7450 5775);
FORCEPROP 1 LAST COMMENT_BODY TRUE
J 0
(-7650 5800);
DISPLAY 0.872340 (-7650 5800);
PAINT GREEN (-7650 5800);
DISPLAY INVISIBLE (-7650 5800);
FORCEPROP 2 LAST PATH I309
J 0
(-8025 5950);
DISPLAY 1.021277 (-8025 5950);
DISPLAY INVISIBLE (-8025 5950);
FORCEADD OFFPAGE..1
(-7775 5850);
FORCEPROP 2 LAST $XR0 50 
J 0
(-8026 5850);
DISPLAY 0.638298 (-8026 5850);
PAINT MONO (-8026 5850);
FORCEPROP 2 LAST CDS_LIB standard
J 0
(-7775 5850);
DISPLAY INVISIBLE (-7775 5850);
FORCEPROP 1 LAST OFFPAGE TRUE
J 0
(-7450 5725);
DISPLAY 0.872340 (-7450 5725);
PAINT GREEN (-7450 5725);
DISPLAY INVISIBLE (-7450 5725);
FORCEPROP 1 LAST COMMENT_BODY TRUE
J 0
(-7650 5750);
DISPLAY 0.872340 (-7650 5750);
PAINT GREEN (-7650 5750);
DISPLAY INVISIBLE (-7650 5750);
FORCEPROP 2 LAST PATH I310
J 0
(-8025 5900);
DISPLAY 1.021277 (-8025 5900);
DISPLAY INVISIBLE (-8025 5900);
FORCEADD OFFPAGE..2
(-1975 3125);
FORCEPROP 2 LAST $XR0 50 
J 0
(-1786 3125);
DISPLAY 0.638298 (-1786 3125);
PAINT MONO (-1786 3125);
FORCEPROP 2 LAST CDS_LIB standard
J 0
(-1975 3125);
DISPLAY INVISIBLE (-1975 3125);
FORCEPROP 1 LAST OFFPAGE TRUE
J 0
(-1650 3000);
DISPLAY 0.872340 (-1650 3000);
PAINT GREEN (-1650 3000);
DISPLAY INVISIBLE (-1650 3000);
FORCEPROP 1 LAST COMMENT_BODY TRUE
J 0
(-2020 3030);
DISPLAY 0.872340 (-2020 3030);
PAINT GREEN (-2020 3030);
DISPLAY INVISIBLE (-2020 3030);
FORCEPROP 2 LAST PATH I311
J 0
(-1775 3175);
DISPLAY 1.021277 (-1775 3175);
DISPLAY INVISIBLE (-1775 3175);
FORCEADD OFFPAGE..2
(-1975 3175);
FORCEPROP 2 LAST $XR0 50 
J 0
(-1786 3175);
DISPLAY 0.638298 (-1786 3175);
PAINT MONO (-1786 3175);
FORCEPROP 2 LAST CDS_LIB standard
J 0
(-1975 3175);
DISPLAY INVISIBLE (-1975 3175);
FORCEPROP 1 LAST OFFPAGE TRUE
J 0
(-1650 3050);
DISPLAY 0.872340 (-1650 3050);
PAINT GREEN (-1650 3050);
DISPLAY INVISIBLE (-1650 3050);
FORCEPROP 1 LAST COMMENT_BODY TRUE
J 0
(-2020 3080);
DISPLAY 0.872340 (-2020 3080);
PAINT GREEN (-2020 3080);
DISPLAY INVISIBLE (-2020 3080);
FORCEPROP 2 LAST PATH I312
J 0
(-1775 3225);
DISPLAY 1.021277 (-1775 3225);
DISPLAY INVISIBLE (-1775 3225);
FORCEADD TAP..6
R 2
(-2950 2900);
FORCEPROP 3 LASTPIN (-3000 2900) SIG_NAME GMI_CPU0_G1_CPU1_G3_TX_DN<0>
J 0
(-2990 2910);
DISPLAY 0.659574 (-2990 2910);
PAINT MONO (-2990 2910);
DISPLAY INVISIBLE (-2990 2910);
FORCEPROP 1 LASTPIN (-3000 2900) BN 0
J 2
(-2948 2908);
DISPLAY 0.489362 (-2948 2908);
PAINT MONO (-2948 2908);
FORCEPROP 2 LAST CDS_LIB mstr_standard
J 0
(-2950 2900);
DISPLAY INVISIBLE (-2950 2900);
FORCEPROP 2 LAST BOM_COST IO_SLOT
J 0
(-3450 3000);
DISPLAY 0.829787 (-3450 3000);
DISPLAY INVISIBLE (-3450 3000);
FORCEPROP 2 LAST ROOM RISER1
J 0
(-3450 2950);
DISPLAY 0.829787 (-3450 2950);
PAINT RED (-3450 2950);
DISPLAY INVISIBLE (-3450 2950);
FORCEPROP 1 LAST BODY_TYPE PLUMBING
J 2
(-2950 2850);
DISPLAY 0.702128 (-2950 2850);
PAINT GREEN (-2950 2850);
DISPLAY INVISIBLE (-2950 2850);
FORCEPROP 1 LAST HDL_TAP TRUE
J 2
(-3275 2775);
DISPLAY 0.702128 (-3275 2775);
PAINT GREEN (-3275 2775);
DISPLAY INVISIBLE (-3275 2775);
FORCEPROP 1 LAST PATH I313
J 2
(-2948 2900);
DISPLAY 0.872340 (-2948 2900);
PAINT GREEN (-2948 2900);
DISPLAY INVISIBLE (-2948 2900);
FORCEADD TAP..6
R 2
(-3100 2850);
FORCEPROP 3 LASTPIN (-3150 2850) SIG_NAME GMI_CPU0_G1_CPU1_G3_TX_DP<1>
J 0
(-3140 2860);
DISPLAY 0.659574 (-3140 2860);
PAINT MONO (-3140 2860);
DISPLAY INVISIBLE (-3140 2860);
FORCEPROP 1 LASTPIN (-3150 2850) BN 1
J 2
(-3098 2858);
DISPLAY 0.489362 (-3098 2858);
PAINT MONO (-3098 2858);
FORCEPROP 2 LAST CDS_LIB mstr_standard
J 0
(-3100 2850);
DISPLAY INVISIBLE (-3100 2850);
FORCEPROP 2 LAST BOM_COST IO_SLOT
J 0
(-3600 2950);
DISPLAY 0.829787 (-3600 2950);
DISPLAY INVISIBLE (-3600 2950);
FORCEPROP 2 LAST ROOM RISER1
J 0
(-3600 2900);
DISPLAY 0.829787 (-3600 2900);
PAINT RED (-3600 2900);
DISPLAY INVISIBLE (-3600 2900);
FORCEPROP 1 LAST BODY_TYPE PLUMBING
J 2
(-3100 2800);
DISPLAY 0.702128 (-3100 2800);
PAINT GREEN (-3100 2800);
DISPLAY INVISIBLE (-3100 2800);
FORCEPROP 1 LAST HDL_TAP TRUE
J 2
(-3425 2725);
DISPLAY 0.702128 (-3425 2725);
PAINT GREEN (-3425 2725);
DISPLAY INVISIBLE (-3425 2725);
FORCEPROP 1 LAST PATH I314
J 2
(-3098 2850);
DISPLAY 0.872340 (-3098 2850);
PAINT GREEN (-3098 2850);
DISPLAY INVISIBLE (-3098 2850);
FORCEADD TAP..6
R 2
(-3100 2950);
FORCEPROP 3 LASTPIN (-3150 2950) SIG_NAME GMI_CPU0_G1_CPU1_G3_TX_DP<0>
J 0
(-3140 2960);
DISPLAY 0.659574 (-3140 2960);
PAINT MONO (-3140 2960);
DISPLAY INVISIBLE (-3140 2960);
FORCEPROP 1 LASTPIN (-3150 2950) BN 0
J 2
(-3098 2958);
DISPLAY 0.489362 (-3098 2958);
PAINT MONO (-3098 2958);
FORCEPROP 2 LAST BOM_COST IO_SLOT
J 0
(-3600 3050);
DISPLAY 0.829787 (-3600 3050);
DISPLAY INVISIBLE (-3600 3050);
FORCEPROP 2 LAST CDS_LIB mstr_standard
J 0
(-3100 2950);
DISPLAY INVISIBLE (-3100 2950);
FORCEPROP 2 LAST ROOM RISER1
J 0
(-3600 3000);
DISPLAY 0.829787 (-3600 3000);
PAINT RED (-3600 3000);
DISPLAY INVISIBLE (-3600 3000);
FORCEPROP 1 LAST BODY_TYPE PLUMBING
J 2
(-3100 2900);
DISPLAY 0.702128 (-3100 2900);
PAINT GREEN (-3100 2900);
DISPLAY INVISIBLE (-3100 2900);
FORCEPROP 1 LAST HDL_TAP TRUE
J 2
(-3425 2825);
DISPLAY 0.702128 (-3425 2825);
PAINT GREEN (-3425 2825);
DISPLAY INVISIBLE (-3425 2825);
FORCEPROP 1 LAST PATH I315
J 2
(-3098 2950);
DISPLAY 0.872340 (-3098 2950);
PAINT GREEN (-3098 2950);
DISPLAY INVISIBLE (-3098 2950);
FORCEADD TAP..6
R 2
(-2950 2800);
FORCEPROP 3 LASTPIN (-3000 2800) SIG_NAME GMI_CPU0_G1_CPU1_G3_TX_DN<1>
J 0
(-2990 2810);
DISPLAY 0.659574 (-2990 2810);
PAINT MONO (-2990 2810);
DISPLAY INVISIBLE (-2990 2810);
FORCEPROP 1 LASTPIN (-3000 2800) BN 1
J 2
(-2948 2808);
DISPLAY 0.489362 (-2948 2808);
PAINT MONO (-2948 2808);
FORCEPROP 2 LAST BOM_COST IO_SLOT
J 0
(-3450 2900);
DISPLAY 0.829787 (-3450 2900);
DISPLAY INVISIBLE (-3450 2900);
FORCEPROP 2 LAST CDS_LIB mstr_standard
J 0
(-2950 2800);
DISPLAY INVISIBLE (-2950 2800);
FORCEPROP 2 LAST ROOM RISER1
J 0
(-3450 2850);
DISPLAY 0.829787 (-3450 2850);
PAINT RED (-3450 2850);
DISPLAY INVISIBLE (-3450 2850);
FORCEPROP 1 LAST BODY_TYPE PLUMBING
J 2
(-2950 2750);
DISPLAY 0.702128 (-2950 2750);
PAINT GREEN (-2950 2750);
DISPLAY INVISIBLE (-2950 2750);
FORCEPROP 1 LAST HDL_TAP TRUE
J 2
(-3275 2675);
DISPLAY 0.702128 (-3275 2675);
PAINT GREEN (-3275 2675);
DISPLAY INVISIBLE (-3275 2675);
FORCEPROP 1 LAST PATH I316
J 2
(-2948 2800);
DISPLAY 0.872340 (-2948 2800);
PAINT GREEN (-2948 2800);
DISPLAY INVISIBLE (-2948 2800);
FORCEADD TAP..6
R 2
(-2950 2700);
FORCEPROP 3 LASTPIN (-3000 2700) SIG_NAME GMI_CPU0_G1_CPU1_G3_TX_DN<2>
J 0
(-2990 2710);
DISPLAY 0.659574 (-2990 2710);
PAINT MONO (-2990 2710);
DISPLAY INVISIBLE (-2990 2710);
FORCEPROP 1 LASTPIN (-3000 2700) BN 2
J 2
(-2948 2708);
DISPLAY 0.489362 (-2948 2708);
PAINT MONO (-2948 2708);
FORCEPROP 2 LAST BOM_COST IO_SLOT
J 0
(-3450 2800);
DISPLAY 0.829787 (-3450 2800);
DISPLAY INVISIBLE (-3450 2800);
FORCEPROP 2 LAST CDS_LIB standard
J 0
(-2950 2700);
DISPLAY INVISIBLE (-2950 2700);
FORCEPROP 2 LAST ROOM RISER1
J 0
(-3450 2750);
DISPLAY 0.829787 (-3450 2750);
PAINT RED (-3450 2750);
DISPLAY INVISIBLE (-3450 2750);
FORCEPROP 1 LAST BODY_TYPE PLUMBING
J 2
(-2950 2650);
DISPLAY 0.702128 (-2950 2650);
PAINT GREEN (-2950 2650);
DISPLAY INVISIBLE (-2950 2650);
FORCEPROP 1 LAST HDL_TAP TRUE
J 2
(-3275 2575);
DISPLAY 0.702128 (-3275 2575);
PAINT GREEN (-3275 2575);
DISPLAY INVISIBLE (-3275 2575);
FORCEPROP 1 LAST PATH I317
J 2
(-2948 2700);
DISPLAY 0.872340 (-2948 2700);
PAINT GREEN (-2948 2700);
DISPLAY INVISIBLE (-2948 2700);
FORCEADD TAP..6
R 2
(-2950 2600);
FORCEPROP 3 LASTPIN (-3000 2600) SIG_NAME GMI_CPU0_G1_CPU1_G3_TX_DN<3>
J 0
(-2990 2610);
DISPLAY 0.659574 (-2990 2610);
PAINT MONO (-2990 2610);
DISPLAY INVISIBLE (-2990 2610);
FORCEPROP 1 LASTPIN (-3000 2600) BN 3
J 2
(-2948 2608);
DISPLAY 0.489362 (-2948 2608);
PAINT MONO (-2948 2608);
FORCEPROP 2 LAST BOM_COST IO_SLOT
J 0
(-3450 2700);
DISPLAY 0.829787 (-3450 2700);
DISPLAY INVISIBLE (-3450 2700);
FORCEPROP 2 LAST CDS_LIB standard
J 0
(-2950 2600);
DISPLAY INVISIBLE (-2950 2600);
FORCEPROP 2 LAST ROOM RISER1
J 0
(-3450 2650);
DISPLAY 0.829787 (-3450 2650);
PAINT RED (-3450 2650);
DISPLAY INVISIBLE (-3450 2650);
FORCEPROP 1 LAST BODY_TYPE PLUMBING
J 2
(-2950 2550);
DISPLAY 0.702128 (-2950 2550);
PAINT GREEN (-2950 2550);
DISPLAY INVISIBLE (-2950 2550);
FORCEPROP 1 LAST HDL_TAP TRUE
J 2
(-3275 2475);
DISPLAY 0.702128 (-3275 2475);
PAINT GREEN (-3275 2475);
DISPLAY INVISIBLE (-3275 2475);
FORCEPROP 1 LAST PATH I318
J 2
(-2948 2600);
DISPLAY 0.872340 (-2948 2600);
PAINT GREEN (-2948 2600);
DISPLAY INVISIBLE (-2948 2600);
FORCEADD TAP..6
R 2
(-3100 2650);
FORCEPROP 3 LASTPIN (-3150 2650) SIG_NAME GMI_CPU0_G1_CPU1_G3_TX_DP<3>
J 0
(-3140 2660);
DISPLAY 0.659574 (-3140 2660);
PAINT MONO (-3140 2660);
DISPLAY INVISIBLE (-3140 2660);
FORCEPROP 1 LASTPIN (-3150 2650) BN 3
J 2
(-3098 2658);
DISPLAY 0.489362 (-3098 2658);
PAINT MONO (-3098 2658);
FORCEPROP 2 LAST CDS_LIB standard
J 0
(-3100 2650);
DISPLAY INVISIBLE (-3100 2650);
FORCEPROP 2 LAST BOM_COST IO_SLOT
J 0
(-3600 2750);
DISPLAY 0.829787 (-3600 2750);
DISPLAY INVISIBLE (-3600 2750);
FORCEPROP 2 LAST ROOM RISER1
J 0
(-3600 2700);
DISPLAY 0.829787 (-3600 2700);
PAINT RED (-3600 2700);
DISPLAY INVISIBLE (-3600 2700);
FORCEPROP 1 LAST BODY_TYPE PLUMBING
J 2
(-3100 2600);
DISPLAY 0.702128 (-3100 2600);
PAINT GREEN (-3100 2600);
DISPLAY INVISIBLE (-3100 2600);
FORCEPROP 1 LAST HDL_TAP TRUE
J 2
(-3425 2525);
DISPLAY 0.702128 (-3425 2525);
PAINT GREEN (-3425 2525);
DISPLAY INVISIBLE (-3425 2525);
FORCEPROP 1 LAST PATH I319
J 2
(-3098 2650);
DISPLAY 0.872340 (-3098 2650);
PAINT GREEN (-3098 2650);
DISPLAY INVISIBLE (-3098 2650);
FORCEADD TAP..6
R 2
(-3100 2750);
FORCEPROP 3 LASTPIN (-3150 2750) SIG_NAME GMI_CPU0_G1_CPU1_G3_TX_DP<2>
J 0
(-3140 2760);
DISPLAY 0.659574 (-3140 2760);
PAINT MONO (-3140 2760);
DISPLAY INVISIBLE (-3140 2760);
FORCEPROP 1 LASTPIN (-3150 2750) BN 2
J 2
(-3098 2758);
DISPLAY 0.489362 (-3098 2758);
PAINT MONO (-3098 2758);
FORCEPROP 2 LAST CDS_LIB standard
J 0
(-3100 2750);
DISPLAY INVISIBLE (-3100 2750);
FORCEPROP 2 LAST BOM_COST IO_SLOT
J 0
(-3600 2850);
DISPLAY 0.829787 (-3600 2850);
DISPLAY INVISIBLE (-3600 2850);
FORCEPROP 2 LAST ROOM RISER1
J 0
(-3600 2800);
DISPLAY 0.829787 (-3600 2800);
PAINT RED (-3600 2800);
DISPLAY INVISIBLE (-3600 2800);
FORCEPROP 1 LAST BODY_TYPE PLUMBING
J 2
(-3100 2700);
DISPLAY 0.702128 (-3100 2700);
PAINT GREEN (-3100 2700);
DISPLAY INVISIBLE (-3100 2700);
FORCEPROP 1 LAST HDL_TAP TRUE
J 2
(-3425 2625);
DISPLAY 0.702128 (-3425 2625);
PAINT GREEN (-3425 2625);
DISPLAY INVISIBLE (-3425 2625);
FORCEPROP 1 LAST PATH I320
J 2
(-3098 2750);
DISPLAY 0.872340 (-3098 2750);
PAINT GREEN (-3098 2750);
DISPLAY INVISIBLE (-3098 2750);
FORCEADD TAP..6
R 2
(-2950 2400);
FORCEPROP 3 LASTPIN (-3000 2400) SIG_NAME GMI_CPU0_G1_CPU1_G3_TX_DN<5>
J 0
(-2990 2410);
DISPLAY 0.659574 (-2990 2410);
PAINT MONO (-2990 2410);
DISPLAY INVISIBLE (-2990 2410);
FORCEPROP 1 LASTPIN (-3000 2400) BN 5
J 2
(-2948 2408);
DISPLAY 0.489362 (-2948 2408);
PAINT MONO (-2948 2408);
FORCEPROP 2 LAST BOM_COST IO_SLOT
J 0
(-3450 2500);
DISPLAY 0.829787 (-3450 2500);
DISPLAY INVISIBLE (-3450 2500);
FORCEPROP 2 LAST CDS_LIB standard
J 0
(-2950 2400);
DISPLAY INVISIBLE (-2950 2400);
FORCEPROP 2 LAST ROOM RISER1
J 0
(-3450 2450);
DISPLAY 0.829787 (-3450 2450);
PAINT RED (-3450 2450);
DISPLAY INVISIBLE (-3450 2450);
FORCEPROP 1 LAST BODY_TYPE PLUMBING
J 2
(-2950 2350);
DISPLAY 0.702128 (-2950 2350);
PAINT GREEN (-2950 2350);
DISPLAY INVISIBLE (-2950 2350);
FORCEPROP 1 LAST HDL_TAP TRUE
J 2
(-3275 2275);
DISPLAY 0.702128 (-3275 2275);
PAINT GREEN (-3275 2275);
DISPLAY INVISIBLE (-3275 2275);
FORCEPROP 1 LAST PATH I321
J 2
(-2948 2400);
DISPLAY 0.872340 (-2948 2400);
PAINT GREEN (-2948 2400);
DISPLAY INVISIBLE (-2948 2400);
FORCEADD TAP..6
R 2
(-2950 2500);
FORCEPROP 3 LASTPIN (-3000 2500) SIG_NAME GMI_CPU0_G1_CPU1_G3_TX_DN<4>
J 0
(-2990 2510);
DISPLAY 0.659574 (-2990 2510);
PAINT MONO (-2990 2510);
DISPLAY INVISIBLE (-2990 2510);
FORCEPROP 1 LASTPIN (-3000 2500) BN 4
J 2
(-2948 2508);
DISPLAY 0.489362 (-2948 2508);
PAINT MONO (-2948 2508);
FORCEPROP 2 LAST BOM_COST IO_SLOT
J 0
(-3450 2600);
DISPLAY 0.829787 (-3450 2600);
DISPLAY INVISIBLE (-3450 2600);
FORCEPROP 2 LAST CDS_LIB standard
J 0
(-2950 2500);
DISPLAY INVISIBLE (-2950 2500);
FORCEPROP 2 LAST ROOM RISER1
J 0
(-3450 2550);
DISPLAY 0.829787 (-3450 2550);
PAINT RED (-3450 2550);
DISPLAY INVISIBLE (-3450 2550);
FORCEPROP 1 LAST BODY_TYPE PLUMBING
J 2
(-2950 2450);
DISPLAY 0.702128 (-2950 2450);
PAINT GREEN (-2950 2450);
DISPLAY INVISIBLE (-2950 2450);
FORCEPROP 1 LAST HDL_TAP TRUE
J 2
(-3275 2375);
DISPLAY 0.702128 (-3275 2375);
PAINT GREEN (-3275 2375);
DISPLAY INVISIBLE (-3275 2375);
FORCEPROP 1 LAST PATH I322
J 2
(-2948 2500);
DISPLAY 0.872340 (-2948 2500);
PAINT GREEN (-2948 2500);
DISPLAY INVISIBLE (-2948 2500);
FORCEADD TAP..6
R 2
(-3100 2350);
FORCEPROP 3 LASTPIN (-3150 2350) SIG_NAME GMI_CPU0_G1_CPU1_G3_TX_DP<6>
J 0
(-3140 2360);
DISPLAY 0.659574 (-3140 2360);
PAINT MONO (-3140 2360);
DISPLAY INVISIBLE (-3140 2360);
FORCEPROP 1 LASTPIN (-3150 2350) BN 6
J 2
(-3098 2358);
DISPLAY 0.489362 (-3098 2358);
PAINT MONO (-3098 2358);
FORCEPROP 2 LAST CDS_LIB standard
J 0
(-3100 2350);
DISPLAY INVISIBLE (-3100 2350);
FORCEPROP 2 LAST BOM_COST IO_SLOT
J 0
(-3600 2450);
DISPLAY 0.829787 (-3600 2450);
DISPLAY INVISIBLE (-3600 2450);
FORCEPROP 2 LAST ROOM RISER1
J 0
(-3600 2400);
DISPLAY 0.829787 (-3600 2400);
PAINT RED (-3600 2400);
DISPLAY INVISIBLE (-3600 2400);
FORCEPROP 1 LAST BODY_TYPE PLUMBING
J 2
(-3100 2300);
DISPLAY 0.702128 (-3100 2300);
PAINT GREEN (-3100 2300);
DISPLAY INVISIBLE (-3100 2300);
FORCEPROP 1 LAST HDL_TAP TRUE
J 2
(-3425 2225);
DISPLAY 0.702128 (-3425 2225);
PAINT GREEN (-3425 2225);
DISPLAY INVISIBLE (-3425 2225);
FORCEPROP 1 LAST PATH I323
J 2
(-3098 2350);
DISPLAY 0.872340 (-3098 2350);
PAINT GREEN (-3098 2350);
DISPLAY INVISIBLE (-3098 2350);
FORCEADD TAP..6
R 2
(-3100 2450);
FORCEPROP 3 LASTPIN (-3150 2450) SIG_NAME GMI_CPU0_G1_CPU1_G3_TX_DP<5>
J 0
(-3140 2460);
DISPLAY 0.659574 (-3140 2460);
PAINT MONO (-3140 2460);
DISPLAY INVISIBLE (-3140 2460);
FORCEPROP 1 LASTPIN (-3150 2450) BN 5
J 2
(-3098 2458);
DISPLAY 0.489362 (-3098 2458);
PAINT MONO (-3098 2458);
FORCEPROP 2 LAST CDS_LIB standard
J 0
(-3100 2450);
DISPLAY INVISIBLE (-3100 2450);
FORCEPROP 2 LAST BOM_COST IO_SLOT
J 0
(-3600 2550);
DISPLAY 0.829787 (-3600 2550);
DISPLAY INVISIBLE (-3600 2550);
FORCEPROP 2 LAST ROOM RISER1
J 0
(-3600 2500);
DISPLAY 0.829787 (-3600 2500);
PAINT RED (-3600 2500);
DISPLAY INVISIBLE (-3600 2500);
FORCEPROP 1 LAST BODY_TYPE PLUMBING
J 2
(-3100 2400);
DISPLAY 0.702128 (-3100 2400);
PAINT GREEN (-3100 2400);
DISPLAY INVISIBLE (-3100 2400);
FORCEPROP 1 LAST HDL_TAP TRUE
J 2
(-3425 2325);
DISPLAY 0.702128 (-3425 2325);
PAINT GREEN (-3425 2325);
DISPLAY INVISIBLE (-3425 2325);
FORCEPROP 1 LAST PATH I324
J 2
(-3098 2450);
DISPLAY 0.872340 (-3098 2450);
PAINT GREEN (-3098 2450);
DISPLAY INVISIBLE (-3098 2450);
FORCEADD TAP..6
R 2
(-3100 2550);
FORCEPROP 3 LASTPIN (-3150 2550) SIG_NAME GMI_CPU0_G1_CPU1_G3_TX_DP<4>
J 0
(-3140 2560);
DISPLAY 0.659574 (-3140 2560);
PAINT MONO (-3140 2560);
DISPLAY INVISIBLE (-3140 2560);
FORCEPROP 1 LASTPIN (-3150 2550) BN 4
J 2
(-3098 2558);
DISPLAY 0.489362 (-3098 2558);
PAINT MONO (-3098 2558);
FORCEPROP 2 LAST CDS_LIB standard
J 0
(-3100 2550);
DISPLAY INVISIBLE (-3100 2550);
FORCEPROP 2 LAST BOM_COST IO_SLOT
J 0
(-3600 2650);
DISPLAY 0.829787 (-3600 2650);
DISPLAY INVISIBLE (-3600 2650);
FORCEPROP 2 LAST ROOM RISER1
J 0
(-3600 2600);
DISPLAY 0.829787 (-3600 2600);
PAINT RED (-3600 2600);
DISPLAY INVISIBLE (-3600 2600);
FORCEPROP 1 LAST BODY_TYPE PLUMBING
J 2
(-3100 2500);
DISPLAY 0.702128 (-3100 2500);
PAINT GREEN (-3100 2500);
DISPLAY INVISIBLE (-3100 2500);
FORCEPROP 1 LAST HDL_TAP TRUE
J 2
(-3425 2425);
DISPLAY 0.702128 (-3425 2425);
PAINT GREEN (-3425 2425);
DISPLAY INVISIBLE (-3425 2425);
FORCEPROP 1 LAST PATH I325
J 2
(-3098 2550);
DISPLAY 0.872340 (-3098 2550);
PAINT GREEN (-3098 2550);
DISPLAY INVISIBLE (-3098 2550);
FORCEADD TAP..6
R 2
(-2950 2200);
FORCEPROP 3 LASTPIN (-3000 2200) SIG_NAME GMI_CPU0_G1_CPU1_G3_TX_DN<7>
J 0
(-2990 2210);
DISPLAY 0.659574 (-2990 2210);
PAINT MONO (-2990 2210);
DISPLAY INVISIBLE (-2990 2210);
FORCEPROP 1 LASTPIN (-3000 2200) BN 7
J 2
(-2948 2208);
DISPLAY 0.489362 (-2948 2208);
PAINT MONO (-2948 2208);
FORCEPROP 2 LAST BOM_COST IO_SLOT
J 0
(-3450 2300);
DISPLAY 0.829787 (-3450 2300);
DISPLAY INVISIBLE (-3450 2300);
FORCEPROP 2 LAST CDS_LIB standard
J 0
(-2950 2200);
DISPLAY INVISIBLE (-2950 2200);
FORCEPROP 2 LAST ROOM RISER1
J 0
(-3450 2250);
DISPLAY 0.829787 (-3450 2250);
PAINT RED (-3450 2250);
DISPLAY INVISIBLE (-3450 2250);
FORCEPROP 1 LAST BODY_TYPE PLUMBING
J 2
(-2950 2150);
DISPLAY 0.702128 (-2950 2150);
PAINT GREEN (-2950 2150);
DISPLAY INVISIBLE (-2950 2150);
FORCEPROP 1 LAST HDL_TAP TRUE
J 2
(-3275 2075);
DISPLAY 0.702128 (-3275 2075);
PAINT GREEN (-3275 2075);
DISPLAY INVISIBLE (-3275 2075);
FORCEPROP 1 LAST PATH I326
J 2
(-2948 2200);
DISPLAY 0.872340 (-2948 2200);
PAINT GREEN (-2948 2200);
DISPLAY INVISIBLE (-2948 2200);
FORCEADD TAP..6
R 2
(-2950 2300);
FORCEPROP 3 LASTPIN (-3000 2300) SIG_NAME GMI_CPU0_G1_CPU1_G3_TX_DN<6>
J 0
(-2990 2310);
DISPLAY 0.659574 (-2990 2310);
PAINT MONO (-2990 2310);
DISPLAY INVISIBLE (-2990 2310);
FORCEPROP 1 LASTPIN (-3000 2300) BN 6
J 2
(-2948 2308);
DISPLAY 0.489362 (-2948 2308);
PAINT MONO (-2948 2308);
FORCEPROP 2 LAST BOM_COST IO_SLOT
J 0
(-3450 2400);
DISPLAY 0.829787 (-3450 2400);
DISPLAY INVISIBLE (-3450 2400);
FORCEPROP 2 LAST CDS_LIB standard
J 0
(-2950 2300);
DISPLAY INVISIBLE (-2950 2300);
FORCEPROP 2 LAST ROOM RISER1
J 0
(-3450 2350);
DISPLAY 0.829787 (-3450 2350);
PAINT RED (-3450 2350);
DISPLAY INVISIBLE (-3450 2350);
FORCEPROP 1 LAST BODY_TYPE PLUMBING
J 2
(-2950 2250);
DISPLAY 0.702128 (-2950 2250);
PAINT GREEN (-2950 2250);
DISPLAY INVISIBLE (-2950 2250);
FORCEPROP 1 LAST HDL_TAP TRUE
J 2
(-3275 2175);
DISPLAY 0.702128 (-3275 2175);
PAINT GREEN (-3275 2175);
DISPLAY INVISIBLE (-3275 2175);
FORCEPROP 1 LAST PATH I327
J 2
(-2948 2300);
DISPLAY 0.872340 (-2948 2300);
PAINT GREEN (-2948 2300);
DISPLAY INVISIBLE (-2948 2300);
FORCEADD TAP..6
R 2
(-2950 2100);
FORCEPROP 3 LASTPIN (-3000 2100) SIG_NAME GMI_CPU0_G1_CPU1_G3_TX_DN<8>
J 0
(-2990 2110);
DISPLAY 0.659574 (-2990 2110);
PAINT MONO (-2990 2110);
DISPLAY INVISIBLE (-2990 2110);
FORCEPROP 1 LASTPIN (-3000 2100) BN 8
J 2
(-2948 2108);
DISPLAY 0.489362 (-2948 2108);
PAINT MONO (-2948 2108);
FORCEPROP 2 LAST BOM_COST IO_SLOT
J 0
(-3450 2200);
DISPLAY 0.829787 (-3450 2200);
DISPLAY INVISIBLE (-3450 2200);
FORCEPROP 2 LAST CDS_LIB standard
J 0
(-2950 2100);
DISPLAY INVISIBLE (-2950 2100);
FORCEPROP 2 LAST ROOM RISER1
J 0
(-3450 2150);
DISPLAY 0.829787 (-3450 2150);
PAINT RED (-3450 2150);
DISPLAY INVISIBLE (-3450 2150);
FORCEPROP 1 LAST BODY_TYPE PLUMBING
J 2
(-2950 2050);
DISPLAY 0.702128 (-2950 2050);
PAINT GREEN (-2950 2050);
DISPLAY INVISIBLE (-2950 2050);
FORCEPROP 1 LAST HDL_TAP TRUE
J 2
(-3275 1975);
DISPLAY 0.702128 (-3275 1975);
PAINT GREEN (-3275 1975);
DISPLAY INVISIBLE (-3275 1975);
FORCEPROP 1 LAST PATH I328
J 2
(-2948 2100);
DISPLAY 0.872340 (-2948 2100);
PAINT GREEN (-2948 2100);
DISPLAY INVISIBLE (-2948 2100);
FORCEADD TAP..6
R 2
(-3100 2150);
FORCEPROP 3 LASTPIN (-3150 2150) SIG_NAME GMI_CPU0_G1_CPU1_G3_TX_DP<8>
J 0
(-3140 2160);
DISPLAY 0.659574 (-3140 2160);
PAINT MONO (-3140 2160);
DISPLAY INVISIBLE (-3140 2160);
FORCEPROP 1 LASTPIN (-3150 2150) BN 8
J 2
(-3098 2158);
DISPLAY 0.489362 (-3098 2158);
PAINT MONO (-3098 2158);
FORCEPROP 2 LAST CDS_LIB standard
J 0
(-3100 2150);
DISPLAY INVISIBLE (-3100 2150);
FORCEPROP 2 LAST BOM_COST IO_SLOT
J 0
(-3600 2250);
DISPLAY 0.829787 (-3600 2250);
DISPLAY INVISIBLE (-3600 2250);
FORCEPROP 2 LAST ROOM RISER1
J 0
(-3600 2200);
DISPLAY 0.829787 (-3600 2200);
PAINT RED (-3600 2200);
DISPLAY INVISIBLE (-3600 2200);
FORCEPROP 1 LAST BODY_TYPE PLUMBING
J 2
(-3100 2100);
DISPLAY 0.702128 (-3100 2100);
PAINT GREEN (-3100 2100);
DISPLAY INVISIBLE (-3100 2100);
FORCEPROP 1 LAST HDL_TAP TRUE
J 2
(-3425 2025);
DISPLAY 0.702128 (-3425 2025);
PAINT GREEN (-3425 2025);
DISPLAY INVISIBLE (-3425 2025);
FORCEPROP 1 LAST PATH I329
J 2
(-3098 2150);
DISPLAY 0.872340 (-3098 2150);
PAINT GREEN (-3098 2150);
DISPLAY INVISIBLE (-3098 2150);
FORCEADD TAP..6
R 2
(-3100 2050);
FORCEPROP 3 LASTPIN (-3150 2050) SIG_NAME GMI_CPU0_G1_CPU1_G3_TX_DP<9>
J 0
(-3140 2060);
DISPLAY 0.659574 (-3140 2060);
PAINT MONO (-3140 2060);
DISPLAY INVISIBLE (-3140 2060);
FORCEPROP 1 LASTPIN (-3150 2050) BN 9
J 2
(-3098 2058);
DISPLAY 0.489362 (-3098 2058);
PAINT MONO (-3098 2058);
FORCEPROP 2 LAST CDS_LIB standard
J 0
(-3100 2050);
DISPLAY INVISIBLE (-3100 2050);
FORCEPROP 2 LAST BOM_COST IO_SLOT
J 0
(-3600 2150);
DISPLAY 0.829787 (-3600 2150);
DISPLAY INVISIBLE (-3600 2150);
FORCEPROP 2 LAST ROOM RISER1
J 0
(-3600 2100);
DISPLAY 0.829787 (-3600 2100);
PAINT RED (-3600 2100);
DISPLAY INVISIBLE (-3600 2100);
FORCEPROP 1 LAST BODY_TYPE PLUMBING
J 2
(-3100 2000);
DISPLAY 0.702128 (-3100 2000);
PAINT GREEN (-3100 2000);
DISPLAY INVISIBLE (-3100 2000);
FORCEPROP 1 LAST HDL_TAP TRUE
J 2
(-3425 1925);
DISPLAY 0.702128 (-3425 1925);
PAINT GREEN (-3425 1925);
DISPLAY INVISIBLE (-3425 1925);
FORCEPROP 1 LAST PATH I330
J 2
(-3098 2050);
DISPLAY 0.872340 (-3098 2050);
PAINT GREEN (-3098 2050);
DISPLAY INVISIBLE (-3098 2050);
FORCEADD TAP..6
R 2
(-3100 2250);
FORCEPROP 3 LASTPIN (-3150 2250) SIG_NAME GMI_CPU0_G1_CPU1_G3_TX_DP<7>
J 0
(-3140 2260);
DISPLAY 0.659574 (-3140 2260);
PAINT MONO (-3140 2260);
DISPLAY INVISIBLE (-3140 2260);
FORCEPROP 1 LASTPIN (-3150 2250) BN 7
J 2
(-3098 2258);
DISPLAY 0.489362 (-3098 2258);
PAINT MONO (-3098 2258);
FORCEPROP 2 LAST CDS_LIB standard
J 0
(-3100 2250);
DISPLAY INVISIBLE (-3100 2250);
FORCEPROP 2 LAST BOM_COST IO_SLOT
J 0
(-3600 2350);
DISPLAY 0.829787 (-3600 2350);
DISPLAY INVISIBLE (-3600 2350);
FORCEPROP 2 LAST ROOM RISER1
J 0
(-3600 2300);
DISPLAY 0.829787 (-3600 2300);
PAINT RED (-3600 2300);
DISPLAY INVISIBLE (-3600 2300);
FORCEPROP 1 LAST BODY_TYPE PLUMBING
J 2
(-3100 2200);
DISPLAY 0.702128 (-3100 2200);
PAINT GREEN (-3100 2200);
DISPLAY INVISIBLE (-3100 2200);
FORCEPROP 1 LAST HDL_TAP TRUE
J 2
(-3425 2125);
DISPLAY 0.702128 (-3425 2125);
PAINT GREEN (-3425 2125);
DISPLAY INVISIBLE (-3425 2125);
FORCEPROP 1 LAST PATH I331
J 2
(-3098 2250);
DISPLAY 0.872340 (-3098 2250);
PAINT GREEN (-3098 2250);
DISPLAY INVISIBLE (-3098 2250);
FORCEADD TAP..6
R 2
(-2950 2000);
FORCEPROP 3 LASTPIN (-3000 2000) SIG_NAME GMI_CPU0_G1_CPU1_G3_TX_DN<9>
J 0
(-2990 2010);
DISPLAY 0.659574 (-2990 2010);
PAINT MONO (-2990 2010);
DISPLAY INVISIBLE (-2990 2010);
FORCEPROP 1 LASTPIN (-3000 2000) BN 9
J 2
(-2948 2008);
DISPLAY 0.489362 (-2948 2008);
PAINT MONO (-2948 2008);
FORCEPROP 2 LAST BOM_COST IO_SLOT
J 0
(-3450 2100);
DISPLAY 0.829787 (-3450 2100);
DISPLAY INVISIBLE (-3450 2100);
FORCEPROP 2 LAST CDS_LIB standard
J 0
(-2950 2000);
DISPLAY INVISIBLE (-2950 2000);
FORCEPROP 2 LAST ROOM RISER1
J 0
(-3450 2050);
DISPLAY 0.829787 (-3450 2050);
PAINT RED (-3450 2050);
DISPLAY INVISIBLE (-3450 2050);
FORCEPROP 1 LAST BODY_TYPE PLUMBING
J 2
(-2950 1950);
DISPLAY 0.702128 (-2950 1950);
PAINT GREEN (-2950 1950);
DISPLAY INVISIBLE (-2950 1950);
FORCEPROP 1 LAST HDL_TAP TRUE
J 2
(-3275 1875);
DISPLAY 0.702128 (-3275 1875);
PAINT GREEN (-3275 1875);
DISPLAY INVISIBLE (-3275 1875);
FORCEPROP 1 LAST PATH I332
J 2
(-2948 2000);
DISPLAY 0.872340 (-2948 2000);
PAINT GREEN (-2948 2000);
DISPLAY INVISIBLE (-2948 2000);
FORCEADD TAP..6
R 2
(-2950 1900);
FORCEPROP 3 LASTPIN (-3000 1900) SIG_NAME GMI_CPU0_G1_CPU1_G3_TX_DN<10>
J 0
(-2990 1910);
DISPLAY 0.659574 (-2990 1910);
PAINT MONO (-2990 1910);
DISPLAY INVISIBLE (-2990 1910);
FORCEPROP 1 LASTPIN (-3000 1900) BN 10
J 2
(-2948 1908);
DISPLAY 0.489362 (-2948 1908);
PAINT MONO (-2948 1908);
FORCEPROP 2 LAST BOM_COST IO_SLOT
J 0
(-3450 2000);
DISPLAY 0.829787 (-3450 2000);
DISPLAY INVISIBLE (-3450 2000);
FORCEPROP 2 LAST CDS_LIB standard
J 0
(-2950 1900);
DISPLAY INVISIBLE (-2950 1900);
FORCEPROP 2 LAST ROOM RISER1
J 0
(-3450 1950);
DISPLAY 0.829787 (-3450 1950);
PAINT RED (-3450 1950);
DISPLAY INVISIBLE (-3450 1950);
FORCEPROP 1 LAST BODY_TYPE PLUMBING
J 2
(-2950 1850);
DISPLAY 0.702128 (-2950 1850);
PAINT GREEN (-2950 1850);
DISPLAY INVISIBLE (-2950 1850);
FORCEPROP 1 LAST HDL_TAP TRUE
J 2
(-3275 1775);
DISPLAY 0.702128 (-3275 1775);
PAINT GREEN (-3275 1775);
DISPLAY INVISIBLE (-3275 1775);
FORCEPROP 1 LAST PATH I333
J 2
(-2948 1900);
DISPLAY 0.872340 (-2948 1900);
PAINT GREEN (-2948 1900);
DISPLAY INVISIBLE (-2948 1900);
FORCEADD TAP..6
R 2
(-2950 1800);
FORCEPROP 3 LASTPIN (-3000 1800) SIG_NAME GMI_CPU0_G1_CPU1_G3_TX_DN<11>
J 0
(-2990 1810);
DISPLAY 0.659574 (-2990 1810);
PAINT MONO (-2990 1810);
DISPLAY INVISIBLE (-2990 1810);
FORCEPROP 1 LASTPIN (-3000 1800) BN 11
J 2
(-2948 1808);
DISPLAY 0.489362 (-2948 1808);
PAINT MONO (-2948 1808);
FORCEPROP 2 LAST BOM_COST IO_SLOT
J 0
(-3450 1900);
DISPLAY 0.829787 (-3450 1900);
DISPLAY INVISIBLE (-3450 1900);
FORCEPROP 2 LAST CDS_LIB standard
J 0
(-2950 1800);
DISPLAY INVISIBLE (-2950 1800);
FORCEPROP 2 LAST ROOM RISER1
J 0
(-3450 1850);
DISPLAY 0.829787 (-3450 1850);
PAINT RED (-3450 1850);
DISPLAY INVISIBLE (-3450 1850);
FORCEPROP 1 LAST BODY_TYPE PLUMBING
J 2
(-2950 1750);
DISPLAY 0.702128 (-2950 1750);
PAINT GREEN (-2950 1750);
DISPLAY INVISIBLE (-2950 1750);
FORCEPROP 1 LAST HDL_TAP TRUE
J 2
(-3275 1675);
DISPLAY 0.702128 (-3275 1675);
PAINT GREEN (-3275 1675);
DISPLAY INVISIBLE (-3275 1675);
FORCEPROP 1 LAST PATH I334
J 2
(-2948 1800);
DISPLAY 0.872340 (-2948 1800);
PAINT GREEN (-2948 1800);
DISPLAY INVISIBLE (-2948 1800);
FORCEADD TAP..6
R 2
(-3100 1850);
FORCEPROP 3 LASTPIN (-3150 1850) SIG_NAME GMI_CPU0_G1_CPU1_G3_TX_DP<11>
J 0
(-3140 1860);
DISPLAY 0.659574 (-3140 1860);
PAINT MONO (-3140 1860);
DISPLAY INVISIBLE (-3140 1860);
FORCEPROP 1 LASTPIN (-3150 1850) BN 11
J 2
(-3098 1858);
DISPLAY 0.489362 (-3098 1858);
PAINT MONO (-3098 1858);
FORCEPROP 2 LAST CDS_LIB standard
J 0
(-3100 1850);
DISPLAY INVISIBLE (-3100 1850);
FORCEPROP 2 LAST BOM_COST IO_SLOT
J 0
(-3600 1950);
DISPLAY 0.829787 (-3600 1950);
DISPLAY INVISIBLE (-3600 1950);
FORCEPROP 2 LAST ROOM RISER1
J 0
(-3600 1900);
DISPLAY 0.829787 (-3600 1900);
PAINT RED (-3600 1900);
DISPLAY INVISIBLE (-3600 1900);
FORCEPROP 1 LAST BODY_TYPE PLUMBING
J 2
(-3100 1800);
DISPLAY 0.702128 (-3100 1800);
PAINT GREEN (-3100 1800);
DISPLAY INVISIBLE (-3100 1800);
FORCEPROP 1 LAST HDL_TAP TRUE
J 2
(-3425 1725);
DISPLAY 0.702128 (-3425 1725);
PAINT GREEN (-3425 1725);
DISPLAY INVISIBLE (-3425 1725);
FORCEPROP 1 LAST PATH I335
J 2
(-3098 1850);
DISPLAY 0.872340 (-3098 1850);
PAINT GREEN (-3098 1850);
DISPLAY INVISIBLE (-3098 1850);
FORCEADD TAP..6
R 2
(-3100 1950);
FORCEPROP 3 LASTPIN (-3150 1950) SIG_NAME GMI_CPU0_G1_CPU1_G3_TX_DP<10>
J 0
(-3140 1960);
DISPLAY 0.659574 (-3140 1960);
PAINT MONO (-3140 1960);
DISPLAY INVISIBLE (-3140 1960);
FORCEPROP 1 LASTPIN (-3150 1950) BN 10
J 2
(-3098 1958);
DISPLAY 0.489362 (-3098 1958);
PAINT MONO (-3098 1958);
FORCEPROP 2 LAST CDS_LIB standard
J 0
(-3100 1950);
DISPLAY INVISIBLE (-3100 1950);
FORCEPROP 2 LAST BOM_COST IO_SLOT
J 0
(-3600 2050);
DISPLAY 0.829787 (-3600 2050);
DISPLAY INVISIBLE (-3600 2050);
FORCEPROP 2 LAST ROOM RISER1
J 0
(-3600 2000);
DISPLAY 0.829787 (-3600 2000);
PAINT RED (-3600 2000);
DISPLAY INVISIBLE (-3600 2000);
FORCEPROP 1 LAST BODY_TYPE PLUMBING
J 2
(-3100 1900);
DISPLAY 0.702128 (-3100 1900);
PAINT GREEN (-3100 1900);
DISPLAY INVISIBLE (-3100 1900);
FORCEPROP 1 LAST HDL_TAP TRUE
J 2
(-3425 1825);
DISPLAY 0.702128 (-3425 1825);
PAINT GREEN (-3425 1825);
DISPLAY INVISIBLE (-3425 1825);
FORCEPROP 1 LAST PATH I336
J 2
(-3098 1950);
DISPLAY 0.872340 (-3098 1950);
PAINT GREEN (-3098 1950);
DISPLAY INVISIBLE (-3098 1950);
FORCEADD TAP..6
R 2
(-2950 1700);
FORCEPROP 3 LASTPIN (-3000 1700) SIG_NAME GMI_CPU0_G1_CPU1_G3_TX_DN<12>
J 0
(-2990 1710);
DISPLAY 0.659574 (-2990 1710);
PAINT MONO (-2990 1710);
DISPLAY INVISIBLE (-2990 1710);
FORCEPROP 1 LASTPIN (-3000 1700) BN 12
J 2
(-2948 1708);
DISPLAY 0.489362 (-2948 1708);
PAINT MONO (-2948 1708);
FORCEPROP 2 LAST BOM_COST IO_SLOT
J 0
(-3450 1800);
DISPLAY 0.829787 (-3450 1800);
DISPLAY INVISIBLE (-3450 1800);
FORCEPROP 2 LAST CDS_LIB standard
J 0
(-2950 1700);
DISPLAY INVISIBLE (-2950 1700);
FORCEPROP 2 LAST ROOM RISER1
J 0
(-3450 1750);
DISPLAY 0.829787 (-3450 1750);
PAINT RED (-3450 1750);
DISPLAY INVISIBLE (-3450 1750);
FORCEPROP 1 LAST BODY_TYPE PLUMBING
J 2
(-2950 1650);
DISPLAY 0.702128 (-2950 1650);
PAINT GREEN (-2950 1650);
DISPLAY INVISIBLE (-2950 1650);
FORCEPROP 1 LAST HDL_TAP TRUE
J 2
(-3275 1575);
DISPLAY 0.702128 (-3275 1575);
PAINT GREEN (-3275 1575);
DISPLAY INVISIBLE (-3275 1575);
FORCEPROP 1 LAST PATH I337
J 2
(-2948 1700);
DISPLAY 0.872340 (-2948 1700);
PAINT GREEN (-2948 1700);
DISPLAY INVISIBLE (-2948 1700);
FORCEADD TAP..6
R 2
(-2950 1600);
FORCEPROP 3 LASTPIN (-3000 1600) SIG_NAME GMI_CPU0_G1_CPU1_G3_TX_DN<13>
J 0
(-2990 1610);
DISPLAY 0.659574 (-2990 1610);
PAINT MONO (-2990 1610);
DISPLAY INVISIBLE (-2990 1610);
FORCEPROP 1 LASTPIN (-3000 1600) BN 13
J 2
(-2948 1608);
DISPLAY 0.489362 (-2948 1608);
PAINT MONO (-2948 1608);
FORCEPROP 2 LAST BOM_COST IO_SLOT
J 0
(-3450 1700);
DISPLAY 0.829787 (-3450 1700);
DISPLAY INVISIBLE (-3450 1700);
FORCEPROP 2 LAST CDS_LIB standard
J 0
(-2950 1600);
DISPLAY INVISIBLE (-2950 1600);
FORCEPROP 2 LAST ROOM RISER1
J 0
(-3450 1650);
DISPLAY 0.829787 (-3450 1650);
PAINT RED (-3450 1650);
DISPLAY INVISIBLE (-3450 1650);
FORCEPROP 1 LAST BODY_TYPE PLUMBING
J 2
(-2950 1550);
DISPLAY 0.702128 (-2950 1550);
PAINT GREEN (-2950 1550);
DISPLAY INVISIBLE (-2950 1550);
FORCEPROP 1 LAST HDL_TAP TRUE
J 2
(-3275 1475);
DISPLAY 0.702128 (-3275 1475);
PAINT GREEN (-3275 1475);
DISPLAY INVISIBLE (-3275 1475);
FORCEPROP 1 LAST PATH I338
J 2
(-2948 1600);
DISPLAY 0.872340 (-2948 1600);
PAINT GREEN (-2948 1600);
DISPLAY INVISIBLE (-2948 1600);
FORCEADD TAP..6
R 2
(-3100 1550);
FORCEPROP 3 LASTPIN (-3150 1550) SIG_NAME GMI_CPU0_G1_CPU1_G3_TX_DP<14>
J 0
(-3140 1560);
DISPLAY 0.659574 (-3140 1560);
PAINT MONO (-3140 1560);
DISPLAY INVISIBLE (-3140 1560);
FORCEPROP 1 LASTPIN (-3150 1550) BN 14
J 2
(-3098 1558);
DISPLAY 0.489362 (-3098 1558);
PAINT MONO (-3098 1558);
FORCEPROP 2 LAST CDS_LIB standard
J 0
(-3100 1550);
DISPLAY INVISIBLE (-3100 1550);
FORCEPROP 2 LAST BOM_COST IO_SLOT
J 0
(-3600 1650);
DISPLAY 0.829787 (-3600 1650);
DISPLAY INVISIBLE (-3600 1650);
FORCEPROP 2 LAST ROOM RISER1
J 0
(-3600 1600);
DISPLAY 0.829787 (-3600 1600);
PAINT RED (-3600 1600);
DISPLAY INVISIBLE (-3600 1600);
FORCEPROP 1 LAST BODY_TYPE PLUMBING
J 2
(-3100 1500);
DISPLAY 0.702128 (-3100 1500);
PAINT GREEN (-3100 1500);
DISPLAY INVISIBLE (-3100 1500);
FORCEPROP 1 LAST HDL_TAP TRUE
J 2
(-3425 1425);
DISPLAY 0.702128 (-3425 1425);
PAINT GREEN (-3425 1425);
DISPLAY INVISIBLE (-3425 1425);
FORCEPROP 1 LAST PATH I339
J 2
(-3098 1550);
DISPLAY 0.872340 (-3098 1550);
PAINT GREEN (-3098 1550);
DISPLAY INVISIBLE (-3098 1550);
FORCEADD TAP..6
R 2
(-3100 1650);
FORCEPROP 3 LASTPIN (-3150 1650) SIG_NAME GMI_CPU0_G1_CPU1_G3_TX_DP<13>
J 0
(-3140 1660);
DISPLAY 0.659574 (-3140 1660);
PAINT MONO (-3140 1660);
DISPLAY INVISIBLE (-3140 1660);
FORCEPROP 1 LASTPIN (-3150 1650) BN 13
J 2
(-3098 1658);
DISPLAY 0.489362 (-3098 1658);
PAINT MONO (-3098 1658);
FORCEPROP 2 LAST CDS_LIB standard
J 0
(-3100 1650);
DISPLAY INVISIBLE (-3100 1650);
FORCEPROP 2 LAST BOM_COST IO_SLOT
J 0
(-3600 1750);
DISPLAY 0.829787 (-3600 1750);
DISPLAY INVISIBLE (-3600 1750);
FORCEPROP 2 LAST ROOM RISER1
J 0
(-3600 1700);
DISPLAY 0.829787 (-3600 1700);
PAINT RED (-3600 1700);
DISPLAY INVISIBLE (-3600 1700);
FORCEPROP 1 LAST BODY_TYPE PLUMBING
J 2
(-3100 1600);
DISPLAY 0.702128 (-3100 1600);
PAINT GREEN (-3100 1600);
DISPLAY INVISIBLE (-3100 1600);
FORCEPROP 1 LAST HDL_TAP TRUE
J 2
(-3425 1525);
DISPLAY 0.702128 (-3425 1525);
PAINT GREEN (-3425 1525);
DISPLAY INVISIBLE (-3425 1525);
FORCEPROP 1 LAST PATH I340
J 2
(-3098 1650);
DISPLAY 0.872340 (-3098 1650);
PAINT GREEN (-3098 1650);
DISPLAY INVISIBLE (-3098 1650);
FORCEADD TAP..6
R 2
(-3100 1750);
FORCEPROP 3 LASTPIN (-3150 1750) SIG_NAME GMI_CPU0_G1_CPU1_G3_TX_DP<12>
J 0
(-3140 1760);
DISPLAY 0.659574 (-3140 1760);
PAINT MONO (-3140 1760);
DISPLAY INVISIBLE (-3140 1760);
FORCEPROP 1 LASTPIN (-3150 1750) BN 12
J 2
(-3098 1758);
DISPLAY 0.489362 (-3098 1758);
PAINT MONO (-3098 1758);
FORCEPROP 2 LAST CDS_LIB standard
J 0
(-3100 1750);
DISPLAY INVISIBLE (-3100 1750);
FORCEPROP 2 LAST BOM_COST IO_SLOT
J 0
(-3600 1850);
DISPLAY 0.829787 (-3600 1850);
DISPLAY INVISIBLE (-3600 1850);
FORCEPROP 2 LAST ROOM RISER1
J 0
(-3600 1800);
DISPLAY 0.829787 (-3600 1800);
PAINT RED (-3600 1800);
DISPLAY INVISIBLE (-3600 1800);
FORCEPROP 1 LAST BODY_TYPE PLUMBING
J 2
(-3100 1700);
DISPLAY 0.702128 (-3100 1700);
PAINT GREEN (-3100 1700);
DISPLAY INVISIBLE (-3100 1700);
FORCEPROP 1 LAST HDL_TAP TRUE
J 2
(-3425 1625);
DISPLAY 0.702128 (-3425 1625);
PAINT GREEN (-3425 1625);
DISPLAY INVISIBLE (-3425 1625);
FORCEPROP 1 LAST PATH I341
J 2
(-3098 1750);
DISPLAY 0.872340 (-3098 1750);
PAINT GREEN (-3098 1750);
DISPLAY INVISIBLE (-3098 1750);
FORCEADD TAP..6
R 2
(-2950 1400);
FORCEPROP 3 LASTPIN (-3000 1400) SIG_NAME GMI_CPU0_G1_CPU1_G3_TX_DN<15>
J 0
(-2990 1410);
DISPLAY 0.659574 (-2990 1410);
PAINT MONO (-2990 1410);
DISPLAY INVISIBLE (-2990 1410);
FORCEPROP 1 LASTPIN (-3000 1400) BN 15
J 2
(-2948 1408);
DISPLAY 0.489362 (-2948 1408);
PAINT MONO (-2948 1408);
FORCEPROP 2 LAST BOM_COST IO_SLOT
J 0
(-3450 1500);
DISPLAY 0.829787 (-3450 1500);
DISPLAY INVISIBLE (-3450 1500);
FORCEPROP 2 LAST CDS_LIB standard
J 0
(-2950 1400);
DISPLAY INVISIBLE (-2950 1400);
FORCEPROP 2 LAST ROOM RISER1
J 0
(-3450 1450);
DISPLAY 0.829787 (-3450 1450);
PAINT RED (-3450 1450);
DISPLAY INVISIBLE (-3450 1450);
FORCEPROP 1 LAST BODY_TYPE PLUMBING
J 2
(-2950 1350);
DISPLAY 0.702128 (-2950 1350);
PAINT GREEN (-2950 1350);
DISPLAY INVISIBLE (-2950 1350);
FORCEPROP 1 LAST HDL_TAP TRUE
J 2
(-3275 1275);
DISPLAY 0.702128 (-3275 1275);
PAINT GREEN (-3275 1275);
DISPLAY INVISIBLE (-3275 1275);
FORCEPROP 1 LAST PATH I342
J 2
(-2948 1400);
DISPLAY 0.872340 (-2948 1400);
PAINT GREEN (-2948 1400);
DISPLAY INVISIBLE (-2948 1400);
FORCEADD TAP..6
R 2
(-2950 1500);
FORCEPROP 3 LASTPIN (-3000 1500) SIG_NAME GMI_CPU0_G1_CPU1_G3_TX_DN<14>
J 0
(-2990 1510);
DISPLAY 0.659574 (-2990 1510);
PAINT MONO (-2990 1510);
DISPLAY INVISIBLE (-2990 1510);
FORCEPROP 1 LASTPIN (-3000 1500) BN 14
J 2
(-2948 1508);
DISPLAY 0.489362 (-2948 1508);
PAINT MONO (-2948 1508);
FORCEPROP 2 LAST BOM_COST IO_SLOT
J 0
(-3450 1600);
DISPLAY 0.829787 (-3450 1600);
DISPLAY INVISIBLE (-3450 1600);
FORCEPROP 2 LAST CDS_LIB standard
J 0
(-2950 1500);
DISPLAY INVISIBLE (-2950 1500);
FORCEPROP 2 LAST ROOM RISER1
J 0
(-3450 1550);
DISPLAY 0.829787 (-3450 1550);
PAINT RED (-3450 1550);
DISPLAY INVISIBLE (-3450 1550);
FORCEPROP 1 LAST BODY_TYPE PLUMBING
J 2
(-2950 1450);
DISPLAY 0.702128 (-2950 1450);
PAINT GREEN (-2950 1450);
DISPLAY INVISIBLE (-2950 1450);
FORCEPROP 1 LAST HDL_TAP TRUE
J 2
(-3275 1375);
DISPLAY 0.702128 (-3275 1375);
PAINT GREEN (-3275 1375);
DISPLAY INVISIBLE (-3275 1375);
FORCEPROP 1 LAST PATH I343
J 2
(-2948 1500);
DISPLAY 0.872340 (-2948 1500);
PAINT GREEN (-2948 1500);
DISPLAY INVISIBLE (-2948 1500);
FORCEADD TAP..6
R 2
(-3100 1450);
FORCEPROP 3 LASTPIN (-3150 1450) SIG_NAME GMI_CPU0_G1_CPU1_G3_TX_DP<15>
J 0
(-3140 1460);
DISPLAY 0.659574 (-3140 1460);
PAINT MONO (-3140 1460);
DISPLAY INVISIBLE (-3140 1460);
FORCEPROP 1 LASTPIN (-3150 1450) BN 15
J 2
(-3098 1458);
DISPLAY 0.489362 (-3098 1458);
PAINT MONO (-3098 1458);
FORCEPROP 2 LAST CDS_LIB standard
J 0
(-3100 1450);
DISPLAY INVISIBLE (-3100 1450);
FORCEPROP 2 LAST BOM_COST IO_SLOT
J 0
(-3600 1550);
DISPLAY 0.829787 (-3600 1550);
DISPLAY INVISIBLE (-3600 1550);
FORCEPROP 2 LAST ROOM RISER1
J 0
(-3600 1500);
DISPLAY 0.829787 (-3600 1500);
PAINT RED (-3600 1500);
DISPLAY INVISIBLE (-3600 1500);
FORCEPROP 1 LAST BODY_TYPE PLUMBING
J 2
(-3100 1400);
DISPLAY 0.702128 (-3100 1400);
PAINT GREEN (-3100 1400);
DISPLAY INVISIBLE (-3100 1400);
FORCEPROP 1 LAST HDL_TAP TRUE
J 2
(-3425 1325);
DISPLAY 0.702128 (-3425 1325);
PAINT GREEN (-3425 1325);
DISPLAY INVISIBLE (-3425 1325);
FORCEPROP 1 LAST PATH I344
J 2
(-3098 1450);
DISPLAY 0.872340 (-3098 1450);
PAINT GREEN (-3098 1450);
DISPLAY INVISIBLE (-3098 1450);
FORCEADD TAP..6
(-6525 2950);
FORCEPROP 3 LASTPIN (-6475 2950) SIG_NAME GMI_CPU1_G3_CPU0_G1_TX_DP<0>
J 0
(-6465 2960);
DISPLAY 0.659574 (-6465 2960);
PAINT MONO (-6465 2960);
DISPLAY INVISIBLE (-6465 2960);
FORCEPROP 1 LASTPIN (-6475 2950) BN 0
J 0
(-6527 2958);
DISPLAY 0.489362 (-6527 2958);
PAINT MONO (-6527 2958);
FORCEPROP 2 LAST CDS_LIB mstr_standard
J 0
(-6525 2950);
DISPLAY INVISIBLE (-6525 2950);
FORCEPROP 1 LAST BODY_TYPE PLUMBING
J 0
(-6525 2900);
DISPLAY 0.574468 (-6525 2900);
PAINT GREEN (-6525 2900);
DISPLAY INVISIBLE (-6525 2900);
FORCEPROP 1 LAST HDL_TAP TRUE
J 0
(-6200 2825);
DISPLAY 0.574468 (-6200 2825);
PAINT GREEN (-6200 2825);
DISPLAY INVISIBLE (-6200 2825);
FORCEPROP 1 LAST PATH I345
J 0
(-6527 2950);
DISPLAY 0.872340 (-6527 2950);
PAINT GREEN (-6527 2950);
DISPLAY INVISIBLE (-6527 2950);
FORCEADD TAP..6
(-6525 2850);
FORCEPROP 3 LASTPIN (-6475 2850) SIG_NAME GMI_CPU1_G3_CPU0_G1_TX_DP<1>
J 0
(-6465 2860);
DISPLAY 0.659574 (-6465 2860);
PAINT MONO (-6465 2860);
DISPLAY INVISIBLE (-6465 2860);
FORCEPROP 1 LASTPIN (-6475 2850) BN 1
J 0
(-6527 2858);
DISPLAY 0.489362 (-6527 2858);
PAINT MONO (-6527 2858);
FORCEPROP 2 LAST CDS_LIB mstr_standard
J 0
(-6525 2850);
DISPLAY INVISIBLE (-6525 2850);
FORCEPROP 1 LAST BODY_TYPE PLUMBING
J 0
(-6525 2800);
DISPLAY 0.574468 (-6525 2800);
PAINT GREEN (-6525 2800);
DISPLAY INVISIBLE (-6525 2800);
FORCEPROP 1 LAST HDL_TAP TRUE
J 0
(-6200 2725);
DISPLAY 0.574468 (-6200 2725);
PAINT GREEN (-6200 2725);
DISPLAY INVISIBLE (-6200 2725);
FORCEPROP 1 LAST PATH I346
J 0
(-6527 2850);
DISPLAY 0.872340 (-6527 2850);
PAINT GREEN (-6527 2850);
DISPLAY INVISIBLE (-6527 2850);
FORCEADD TAP..6
(-6675 2900);
FORCEPROP 3 LASTPIN (-6625 2900) SIG_NAME GMI_CPU1_G3_CPU0_G1_TX_DN<0>
J 0
(-6615 2910);
DISPLAY 0.659574 (-6615 2910);
PAINT MONO (-6615 2910);
DISPLAY INVISIBLE (-6615 2910);
FORCEPROP 1 LASTPIN (-6625 2900) BN 0
J 0
(-6677 2908);
DISPLAY 0.489362 (-6677 2908);
PAINT MONO (-6677 2908);
FORCEPROP 2 LAST CDS_LIB mstr_standard
J 0
(-6675 2900);
DISPLAY INVISIBLE (-6675 2900);
FORCEPROP 1 LAST BODY_TYPE PLUMBING
J 0
(-6675 2850);
DISPLAY 0.574468 (-6675 2850);
PAINT GREEN (-6675 2850);
DISPLAY INVISIBLE (-6675 2850);
FORCEPROP 1 LAST HDL_TAP TRUE
J 0
(-6350 2775);
DISPLAY 0.574468 (-6350 2775);
PAINT GREEN (-6350 2775);
DISPLAY INVISIBLE (-6350 2775);
FORCEPROP 1 LAST PATH I347
J 0
(-6677 2900);
DISPLAY 0.872340 (-6677 2900);
PAINT GREEN (-6677 2900);
DISPLAY INVISIBLE (-6677 2900);
FORCEADD TAP..6
(-6525 2750);
FORCEPROP 3 LASTPIN (-6475 2750) SIG_NAME GMI_CPU1_G3_CPU0_G1_TX_DP<2>
J 0
(-6465 2760);
DISPLAY 0.659574 (-6465 2760);
PAINT MONO (-6465 2760);
DISPLAY INVISIBLE (-6465 2760);
FORCEPROP 1 LASTPIN (-6475 2750) BN 2
J 0
(-6527 2758);
DISPLAY 0.489362 (-6527 2758);
PAINT MONO (-6527 2758);
FORCEPROP 2 LAST CDS_LIB mstr_standard
J 0
(-6525 2750);
DISPLAY INVISIBLE (-6525 2750);
FORCEPROP 1 LAST BODY_TYPE PLUMBING
J 0
(-6525 2700);
DISPLAY 0.574468 (-6525 2700);
PAINT GREEN (-6525 2700);
DISPLAY INVISIBLE (-6525 2700);
FORCEPROP 1 LAST HDL_TAP TRUE
J 0
(-6200 2625);
DISPLAY 0.574468 (-6200 2625);
PAINT GREEN (-6200 2625);
DISPLAY INVISIBLE (-6200 2625);
FORCEPROP 1 LAST PATH I348
J 0
(-6527 2750);
DISPLAY 0.872340 (-6527 2750);
PAINT GREEN (-6527 2750);
DISPLAY INVISIBLE (-6527 2750);
FORCEADD TAP..6
(-6525 2650);
FORCEPROP 3 LASTPIN (-6475 2650) SIG_NAME GMI_CPU1_G3_CPU0_G1_TX_DP<3>
J 0
(-6465 2660);
DISPLAY 0.659574 (-6465 2660);
PAINT MONO (-6465 2660);
DISPLAY INVISIBLE (-6465 2660);
FORCEPROP 1 LASTPIN (-6475 2650) BN 3
J 0
(-6527 2658);
DISPLAY 0.489362 (-6527 2658);
PAINT MONO (-6527 2658);
FORCEPROP 2 LAST CDS_LIB standard
J 0
(-6525 2650);
DISPLAY INVISIBLE (-6525 2650);
FORCEPROP 1 LAST BODY_TYPE PLUMBING
J 0
(-6525 2600);
DISPLAY 0.574468 (-6525 2600);
PAINT GREEN (-6525 2600);
DISPLAY INVISIBLE (-6525 2600);
FORCEPROP 1 LAST HDL_TAP TRUE
J 0
(-6200 2525);
DISPLAY 0.574468 (-6200 2525);
PAINT GREEN (-6200 2525);
DISPLAY INVISIBLE (-6200 2525);
FORCEPROP 1 LAST PATH I349
J 0
(-6527 2650);
DISPLAY 0.872340 (-6527 2650);
PAINT GREEN (-6527 2650);
DISPLAY INVISIBLE (-6527 2650);
FORCEADD TAP..6
(-6675 2700);
FORCEPROP 3 LASTPIN (-6625 2700) SIG_NAME GMI_CPU1_G3_CPU0_G1_TX_DN<2>
J 0
(-6615 2710);
DISPLAY 0.659574 (-6615 2710);
PAINT MONO (-6615 2710);
DISPLAY INVISIBLE (-6615 2710);
FORCEPROP 1 LASTPIN (-6625 2700) BN 2
J 0
(-6677 2708);
DISPLAY 0.489362 (-6677 2708);
PAINT MONO (-6677 2708);
FORCEPROP 2 LAST CDS_LIB standard
J 0
(-6675 2700);
DISPLAY INVISIBLE (-6675 2700);
FORCEPROP 1 LAST BODY_TYPE PLUMBING
J 0
(-6675 2650);
DISPLAY 0.574468 (-6675 2650);
PAINT GREEN (-6675 2650);
DISPLAY INVISIBLE (-6675 2650);
FORCEPROP 1 LAST HDL_TAP TRUE
J 0
(-6350 2575);
DISPLAY 0.574468 (-6350 2575);
PAINT GREEN (-6350 2575);
DISPLAY INVISIBLE (-6350 2575);
FORCEPROP 1 LAST PATH I350
J 0
(-6677 2700);
DISPLAY 0.872340 (-6677 2700);
PAINT GREEN (-6677 2700);
DISPLAY INVISIBLE (-6677 2700);
FORCEADD TAP..6
(-6675 2800);
FORCEPROP 3 LASTPIN (-6625 2800) SIG_NAME GMI_CPU1_G3_CPU0_G1_TX_DN<1>
J 0
(-6615 2810);
DISPLAY 0.659574 (-6615 2810);
PAINT MONO (-6615 2810);
DISPLAY INVISIBLE (-6615 2810);
FORCEPROP 1 LASTPIN (-6625 2800) BN 1
J 0
(-6677 2808);
DISPLAY 0.489362 (-6677 2808);
PAINT MONO (-6677 2808);
FORCEPROP 2 LAST CDS_LIB mstr_standard
J 0
(-6675 2800);
DISPLAY INVISIBLE (-6675 2800);
FORCEPROP 1 LAST BODY_TYPE PLUMBING
J 0
(-6675 2750);
DISPLAY 0.574468 (-6675 2750);
PAINT GREEN (-6675 2750);
DISPLAY INVISIBLE (-6675 2750);
FORCEPROP 1 LAST HDL_TAP TRUE
J 0
(-6350 2675);
DISPLAY 0.574468 (-6350 2675);
PAINT GREEN (-6350 2675);
DISPLAY INVISIBLE (-6350 2675);
FORCEPROP 1 LAST PATH I351
J 0
(-6677 2800);
DISPLAY 0.872340 (-6677 2800);
PAINT GREEN (-6677 2800);
DISPLAY INVISIBLE (-6677 2800);
FORCEADD TAP..6
(-6675 2600);
FORCEPROP 3 LASTPIN (-6625 2600) SIG_NAME GMI_CPU1_G3_CPU0_G1_TX_DN<3>
J 0
(-6615 2610);
DISPLAY 0.659574 (-6615 2610);
PAINT MONO (-6615 2610);
DISPLAY INVISIBLE (-6615 2610);
FORCEPROP 1 LASTPIN (-6625 2600) BN 3
J 0
(-6677 2608);
DISPLAY 0.489362 (-6677 2608);
PAINT MONO (-6677 2608);
FORCEPROP 2 LAST CDS_LIB standard
J 0
(-6675 2600);
DISPLAY INVISIBLE (-6675 2600);
FORCEPROP 1 LAST BODY_TYPE PLUMBING
J 0
(-6675 2550);
DISPLAY 0.574468 (-6675 2550);
PAINT GREEN (-6675 2550);
DISPLAY INVISIBLE (-6675 2550);
FORCEPROP 1 LAST HDL_TAP TRUE
J 0
(-6350 2475);
DISPLAY 0.574468 (-6350 2475);
PAINT GREEN (-6350 2475);
DISPLAY INVISIBLE (-6350 2475);
FORCEPROP 1 LAST PATH I352
J 0
(-6677 2600);
DISPLAY 0.872340 (-6677 2600);
PAINT GREEN (-6677 2600);
DISPLAY INVISIBLE (-6677 2600);
FORCEADD TAP..6
(-6525 2550);
FORCEPROP 3 LASTPIN (-6475 2550) SIG_NAME GMI_CPU1_G3_CPU0_G1_TX_DP<4>
J 0
(-6465 2560);
DISPLAY 0.659574 (-6465 2560);
PAINT MONO (-6465 2560);
DISPLAY INVISIBLE (-6465 2560);
FORCEPROP 1 LASTPIN (-6475 2550) BN 4
J 0
(-6527 2558);
DISPLAY 0.489362 (-6527 2558);
PAINT MONO (-6527 2558);
FORCEPROP 2 LAST CDS_LIB standard
J 0
(-6525 2550);
DISPLAY INVISIBLE (-6525 2550);
FORCEPROP 1 LAST BODY_TYPE PLUMBING
J 0
(-6525 2500);
DISPLAY 0.574468 (-6525 2500);
PAINT GREEN (-6525 2500);
DISPLAY INVISIBLE (-6525 2500);
FORCEPROP 1 LAST HDL_TAP TRUE
J 0
(-6200 2425);
DISPLAY 0.574468 (-6200 2425);
PAINT GREEN (-6200 2425);
DISPLAY INVISIBLE (-6200 2425);
FORCEPROP 1 LAST PATH I353
J 0
(-6527 2550);
DISPLAY 0.872340 (-6527 2550);
PAINT GREEN (-6527 2550);
DISPLAY INVISIBLE (-6527 2550);
FORCEADD TAP..6
(-6525 2450);
FORCEPROP 3 LASTPIN (-6475 2450) SIG_NAME GMI_CPU1_G3_CPU0_G1_TX_DP<5>
J 0
(-6465 2460);
DISPLAY 0.659574 (-6465 2460);
PAINT MONO (-6465 2460);
DISPLAY INVISIBLE (-6465 2460);
FORCEPROP 1 LASTPIN (-6475 2450) BN 5
J 0
(-6527 2458);
DISPLAY 0.489362 (-6527 2458);
PAINT MONO (-6527 2458);
FORCEPROP 2 LAST CDS_LIB standard
J 0
(-6525 2450);
DISPLAY INVISIBLE (-6525 2450);
FORCEPROP 1 LAST BODY_TYPE PLUMBING
J 0
(-6525 2400);
DISPLAY 0.574468 (-6525 2400);
PAINT GREEN (-6525 2400);
DISPLAY INVISIBLE (-6525 2400);
FORCEPROP 1 LAST HDL_TAP TRUE
J 0
(-6200 2325);
DISPLAY 0.574468 (-6200 2325);
PAINT GREEN (-6200 2325);
DISPLAY INVISIBLE (-6200 2325);
FORCEPROP 1 LAST PATH I354
J 0
(-6527 2450);
DISPLAY 0.872340 (-6527 2450);
PAINT GREEN (-6527 2450);
DISPLAY INVISIBLE (-6527 2450);
FORCEADD TAP..6
(-6525 2350);
FORCEPROP 3 LASTPIN (-6475 2350) SIG_NAME GMI_CPU1_G3_CPU0_G1_TX_DP<6>
J 0
(-6465 2360);
DISPLAY 0.659574 (-6465 2360);
PAINT MONO (-6465 2360);
DISPLAY INVISIBLE (-6465 2360);
FORCEPROP 1 LASTPIN (-6475 2350) BN 6
J 0
(-6527 2358);
DISPLAY 0.489362 (-6527 2358);
PAINT MONO (-6527 2358);
FORCEPROP 2 LAST CDS_LIB standard
J 0
(-6525 2350);
DISPLAY INVISIBLE (-6525 2350);
FORCEPROP 1 LAST BODY_TYPE PLUMBING
J 0
(-6525 2300);
DISPLAY 0.574468 (-6525 2300);
PAINT GREEN (-6525 2300);
DISPLAY INVISIBLE (-6525 2300);
FORCEPROP 1 LAST HDL_TAP TRUE
J 0
(-6200 2225);
DISPLAY 0.574468 (-6200 2225);
PAINT GREEN (-6200 2225);
DISPLAY INVISIBLE (-6200 2225);
FORCEPROP 1 LAST PATH I355
J 0
(-6527 2350);
DISPLAY 0.872340 (-6527 2350);
PAINT GREEN (-6527 2350);
DISPLAY INVISIBLE (-6527 2350);
FORCEADD TAP..6
(-6675 2500);
FORCEPROP 3 LASTPIN (-6625 2500) SIG_NAME GMI_CPU1_G3_CPU0_G1_TX_DN<4>
J 0
(-6615 2510);
DISPLAY 0.659574 (-6615 2510);
PAINT MONO (-6615 2510);
DISPLAY INVISIBLE (-6615 2510);
FORCEPROP 1 LASTPIN (-6625 2500) BN 4
J 0
(-6677 2508);
DISPLAY 0.489362 (-6677 2508);
PAINT MONO (-6677 2508);
FORCEPROP 2 LAST CDS_LIB standard
J 0
(-6675 2500);
DISPLAY INVISIBLE (-6675 2500);
FORCEPROP 1 LAST BODY_TYPE PLUMBING
J 0
(-6675 2450);
DISPLAY 0.574468 (-6675 2450);
PAINT GREEN (-6675 2450);
DISPLAY INVISIBLE (-6675 2450);
FORCEPROP 1 LAST HDL_TAP TRUE
J 0
(-6350 2375);
DISPLAY 0.574468 (-6350 2375);
PAINT GREEN (-6350 2375);
DISPLAY INVISIBLE (-6350 2375);
FORCEPROP 1 LAST PATH I356
J 0
(-6677 2500);
DISPLAY 0.872340 (-6677 2500);
PAINT GREEN (-6677 2500);
DISPLAY INVISIBLE (-6677 2500);
FORCEADD TAP..6
(-6675 2400);
FORCEPROP 3 LASTPIN (-6625 2400) SIG_NAME GMI_CPU1_G3_CPU0_G1_TX_DN<5>
J 0
(-6615 2410);
DISPLAY 0.659574 (-6615 2410);
PAINT MONO (-6615 2410);
DISPLAY INVISIBLE (-6615 2410);
FORCEPROP 1 LASTPIN (-6625 2400) BN 5
J 0
(-6677 2408);
DISPLAY 0.489362 (-6677 2408);
PAINT MONO (-6677 2408);
FORCEPROP 2 LAST CDS_LIB standard
J 0
(-6675 2400);
DISPLAY INVISIBLE (-6675 2400);
FORCEPROP 1 LAST BODY_TYPE PLUMBING
J 0
(-6675 2350);
DISPLAY 0.574468 (-6675 2350);
PAINT GREEN (-6675 2350);
DISPLAY INVISIBLE (-6675 2350);
FORCEPROP 1 LAST HDL_TAP TRUE
J 0
(-6350 2275);
DISPLAY 0.574468 (-6350 2275);
PAINT GREEN (-6350 2275);
DISPLAY INVISIBLE (-6350 2275);
FORCEPROP 1 LAST PATH I357
J 0
(-6677 2400);
DISPLAY 0.872340 (-6677 2400);
PAINT GREEN (-6677 2400);
DISPLAY INVISIBLE (-6677 2400);
FORCEADD TAP..6
(-6525 2250);
FORCEPROP 3 LASTPIN (-6475 2250) SIG_NAME GMI_CPU1_G3_CPU0_G1_TX_DP<7>
J 0
(-6465 2260);
DISPLAY 0.659574 (-6465 2260);
PAINT MONO (-6465 2260);
DISPLAY INVISIBLE (-6465 2260);
FORCEPROP 1 LASTPIN (-6475 2250) BN 7
J 0
(-6527 2258);
DISPLAY 0.489362 (-6527 2258);
PAINT MONO (-6527 2258);
FORCEPROP 2 LAST CDS_LIB standard
J 0
(-6525 2250);
DISPLAY INVISIBLE (-6525 2250);
FORCEPROP 1 LAST BODY_TYPE PLUMBING
J 0
(-6525 2200);
DISPLAY 0.574468 (-6525 2200);
PAINT GREEN (-6525 2200);
DISPLAY INVISIBLE (-6525 2200);
FORCEPROP 1 LAST HDL_TAP TRUE
J 0
(-6200 2125);
DISPLAY 0.574468 (-6200 2125);
PAINT GREEN (-6200 2125);
DISPLAY INVISIBLE (-6200 2125);
FORCEPROP 1 LAST PATH I358
J 0
(-6527 2250);
DISPLAY 0.872340 (-6527 2250);
PAINT GREEN (-6527 2250);
DISPLAY INVISIBLE (-6527 2250);
FORCEADD TAP..6
(-6525 2150);
FORCEPROP 3 LASTPIN (-6475 2150) SIG_NAME GMI_CPU1_G3_CPU0_G1_TX_DP<8>
J 0
(-6465 2160);
DISPLAY 0.659574 (-6465 2160);
PAINT MONO (-6465 2160);
DISPLAY INVISIBLE (-6465 2160);
FORCEPROP 1 LASTPIN (-6475 2150) BN 8
J 0
(-6527 2158);
DISPLAY 0.489362 (-6527 2158);
PAINT MONO (-6527 2158);
FORCEPROP 2 LAST CDS_LIB standard
J 0
(-6525 2150);
DISPLAY INVISIBLE (-6525 2150);
FORCEPROP 1 LAST BODY_TYPE PLUMBING
J 0
(-6525 2100);
DISPLAY 0.574468 (-6525 2100);
PAINT GREEN (-6525 2100);
DISPLAY INVISIBLE (-6525 2100);
FORCEPROP 1 LAST HDL_TAP TRUE
J 0
(-6200 2025);
DISPLAY 0.574468 (-6200 2025);
PAINT GREEN (-6200 2025);
DISPLAY INVISIBLE (-6200 2025);
FORCEPROP 1 LAST PATH I359
J 0
(-6527 2150);
DISPLAY 0.872340 (-6527 2150);
PAINT GREEN (-6527 2150);
DISPLAY INVISIBLE (-6527 2150);
FORCEADD TAP..6
(-6525 2050);
FORCEPROP 3 LASTPIN (-6475 2050) SIG_NAME GMI_CPU1_G3_CPU0_G1_TX_DP<9>
J 0
(-6465 2060);
DISPLAY 0.659574 (-6465 2060);
PAINT MONO (-6465 2060);
DISPLAY INVISIBLE (-6465 2060);
FORCEPROP 1 LASTPIN (-6475 2050) BN 9
J 0
(-6527 2058);
DISPLAY 0.489362 (-6527 2058);
PAINT MONO (-6527 2058);
FORCEPROP 2 LAST CDS_LIB standard
J 0
(-6525 2050);
DISPLAY INVISIBLE (-6525 2050);
FORCEPROP 1 LAST BODY_TYPE PLUMBING
J 0
(-6525 2000);
DISPLAY 0.574468 (-6525 2000);
PAINT GREEN (-6525 2000);
DISPLAY INVISIBLE (-6525 2000);
FORCEPROP 1 LAST HDL_TAP TRUE
J 0
(-6200 1925);
DISPLAY 0.574468 (-6200 1925);
PAINT GREEN (-6200 1925);
DISPLAY INVISIBLE (-6200 1925);
FORCEPROP 1 LAST PATH I360
J 0
(-6527 2050);
DISPLAY 0.872340 (-6527 2050);
PAINT GREEN (-6527 2050);
DISPLAY INVISIBLE (-6527 2050);
FORCEADD TAP..6
(-6675 2200);
FORCEPROP 3 LASTPIN (-6625 2200) SIG_NAME GMI_CPU1_G3_CPU0_G1_TX_DN<7>
J 0
(-6615 2210);
DISPLAY 0.659574 (-6615 2210);
PAINT MONO (-6615 2210);
DISPLAY INVISIBLE (-6615 2210);
FORCEPROP 1 LASTPIN (-6625 2200) BN 7
J 0
(-6677 2208);
DISPLAY 0.489362 (-6677 2208);
PAINT MONO (-6677 2208);
FORCEPROP 2 LAST CDS_LIB standard
J 0
(-6675 2200);
DISPLAY INVISIBLE (-6675 2200);
FORCEPROP 1 LAST BODY_TYPE PLUMBING
J 0
(-6675 2150);
DISPLAY 0.574468 (-6675 2150);
PAINT GREEN (-6675 2150);
DISPLAY INVISIBLE (-6675 2150);
FORCEPROP 1 LAST HDL_TAP TRUE
J 0
(-6350 2075);
DISPLAY 0.574468 (-6350 2075);
PAINT GREEN (-6350 2075);
DISPLAY INVISIBLE (-6350 2075);
FORCEPROP 1 LAST PATH I361
J 0
(-6677 2200);
DISPLAY 0.872340 (-6677 2200);
PAINT GREEN (-6677 2200);
DISPLAY INVISIBLE (-6677 2200);
FORCEADD TAP..6
(-6675 2300);
FORCEPROP 3 LASTPIN (-6625 2300) SIG_NAME GMI_CPU1_G3_CPU0_G1_TX_DN<6>
J 0
(-6615 2310);
DISPLAY 0.659574 (-6615 2310);
PAINT MONO (-6615 2310);
DISPLAY INVISIBLE (-6615 2310);
FORCEPROP 1 LASTPIN (-6625 2300) BN 6
J 0
(-6677 2308);
DISPLAY 0.489362 (-6677 2308);
PAINT MONO (-6677 2308);
FORCEPROP 2 LAST CDS_LIB standard
J 0
(-6675 2300);
DISPLAY INVISIBLE (-6675 2300);
FORCEPROP 1 LAST BODY_TYPE PLUMBING
J 0
(-6675 2250);
DISPLAY 0.574468 (-6675 2250);
PAINT GREEN (-6675 2250);
DISPLAY INVISIBLE (-6675 2250);
FORCEPROP 1 LAST HDL_TAP TRUE
J 0
(-6350 2175);
DISPLAY 0.574468 (-6350 2175);
PAINT GREEN (-6350 2175);
DISPLAY INVISIBLE (-6350 2175);
FORCEPROP 1 LAST PATH I362
J 0
(-6677 2300);
DISPLAY 0.872340 (-6677 2300);
PAINT GREEN (-6677 2300);
DISPLAY INVISIBLE (-6677 2300);
FORCEADD TAP..6
(-6675 2100);
FORCEPROP 3 LASTPIN (-6625 2100) SIG_NAME GMI_CPU1_G3_CPU0_G1_TX_DN<8>
J 0
(-6615 2110);
DISPLAY 0.659574 (-6615 2110);
PAINT MONO (-6615 2110);
DISPLAY INVISIBLE (-6615 2110);
FORCEPROP 1 LASTPIN (-6625 2100) BN 8
J 0
(-6677 2108);
DISPLAY 0.489362 (-6677 2108);
PAINT MONO (-6677 2108);
FORCEPROP 2 LAST CDS_LIB standard
J 0
(-6675 2100);
DISPLAY INVISIBLE (-6675 2100);
FORCEPROP 1 LAST BODY_TYPE PLUMBING
J 0
(-6675 2050);
DISPLAY 0.574468 (-6675 2050);
PAINT GREEN (-6675 2050);
DISPLAY INVISIBLE (-6675 2050);
FORCEPROP 1 LAST HDL_TAP TRUE
J 0
(-6350 1975);
DISPLAY 0.574468 (-6350 1975);
PAINT GREEN (-6350 1975);
DISPLAY INVISIBLE (-6350 1975);
FORCEPROP 1 LAST PATH I363
J 0
(-6677 2100);
DISPLAY 0.872340 (-6677 2100);
PAINT GREEN (-6677 2100);
DISPLAY INVISIBLE (-6677 2100);
FORCEADD OFFPAGE..1
(-7625 3175);
FORCEPROP 2 LAST $XR0 50 
J 0
(-7846 3175);
DISPLAY 0.638298 (-7846 3175);
PAINT MONO (-7846 3175);
FORCEPROP 2 LAST CDS_LIB standard
J 0
(-7625 3175);
DISPLAY INVISIBLE (-7625 3175);
FORCEPROP 1 LAST OFFPAGE TRUE
J 0
(-7300 3050);
DISPLAY 0.872340 (-7300 3050);
PAINT GREEN (-7300 3050);
DISPLAY INVISIBLE (-7300 3050);
FORCEPROP 1 LAST COMMENT_BODY TRUE
J 0
(-7500 3075);
DISPLAY 0.872340 (-7500 3075);
PAINT GREEN (-7500 3075);
DISPLAY INVISIBLE (-7500 3075);
FORCEPROP 2 LAST PATH I364
J 0
(-7825 3225);
DISPLAY 1.021277 (-7825 3225);
DISPLAY INVISIBLE (-7825 3225);
FORCEADD OFFPAGE..1
(-7625 3125);
FORCEPROP 2 LASTPIN (-7575 3125) SIG_NAME GMI_CPU1_G3_CPU0_G1_TX_DN<15:0>
J 0
(-7585 3135);
DISPLAY 0.489362 (-7585 3135);
FORCEPROP 2 LAST $XR0 50 
J 0
(-7846 3125);
DISPLAY 0.638298 (-7846 3125);
PAINT MONO (-7846 3125);
FORCEPROP 2 LAST CDS_LIB standard
J 0
(-7625 3125);
DISPLAY INVISIBLE (-7625 3125);
FORCEPROP 1 LAST OFFPAGE TRUE
J 0
(-7300 3000);
DISPLAY 0.872340 (-7300 3000);
PAINT GREEN (-7300 3000);
DISPLAY INVISIBLE (-7300 3000);
FORCEPROP 1 LAST COMMENT_BODY TRUE
J 0
(-7500 3025);
DISPLAY 0.872340 (-7500 3025);
PAINT GREEN (-7500 3025);
DISPLAY INVISIBLE (-7500 3025);
FORCEPROP 2 LAST PATH I365
J 0
(-7825 3175);
DISPLAY 1.021277 (-7825 3175);
DISPLAY INVISIBLE (-7825 3175);
FORCEADD TAP..6
(-6525 1950);
FORCEPROP 3 LASTPIN (-6475 1950) SIG_NAME GMI_CPU1_G3_CPU0_G1_TX_DP<10>
J 0
(-6465 1960);
DISPLAY 0.659574 (-6465 1960);
PAINT MONO (-6465 1960);
DISPLAY INVISIBLE (-6465 1960);
FORCEPROP 1 LASTPIN (-6475 1950) BN 10
J 0
(-6527 1958);
DISPLAY 0.489362 (-6527 1958);
PAINT MONO (-6527 1958);
FORCEPROP 2 LAST CDS_LIB standard
J 0
(-6525 1950);
DISPLAY INVISIBLE (-6525 1950);
FORCEPROP 1 LAST BODY_TYPE PLUMBING
J 0
(-6525 1900);
DISPLAY 0.574468 (-6525 1900);
PAINT GREEN (-6525 1900);
DISPLAY INVISIBLE (-6525 1900);
FORCEPROP 1 LAST HDL_TAP TRUE
J 0
(-6200 1825);
DISPLAY 0.574468 (-6200 1825);
PAINT GREEN (-6200 1825);
DISPLAY INVISIBLE (-6200 1825);
FORCEPROP 1 LAST PATH I366
J 0
(-6527 1950);
DISPLAY 0.872340 (-6527 1950);
PAINT GREEN (-6527 1950);
DISPLAY INVISIBLE (-6527 1950);
FORCEADD TAP..6
(-6525 1850);
FORCEPROP 3 LASTPIN (-6475 1850) SIG_NAME GMI_CPU1_G3_CPU0_G1_TX_DP<11>
J 0
(-6465 1860);
DISPLAY 0.659574 (-6465 1860);
PAINT MONO (-6465 1860);
DISPLAY INVISIBLE (-6465 1860);
FORCEPROP 1 LASTPIN (-6475 1850) BN 11
J 0
(-6527 1858);
DISPLAY 0.489362 (-6527 1858);
PAINT MONO (-6527 1858);
FORCEPROP 2 LAST CDS_LIB standard
J 0
(-6525 1850);
DISPLAY INVISIBLE (-6525 1850);
FORCEPROP 1 LAST BODY_TYPE PLUMBING
J 0
(-6525 1800);
DISPLAY 0.574468 (-6525 1800);
PAINT GREEN (-6525 1800);
DISPLAY INVISIBLE (-6525 1800);
FORCEPROP 1 LAST HDL_TAP TRUE
J 0
(-6200 1725);
DISPLAY 0.574468 (-6200 1725);
PAINT GREEN (-6200 1725);
DISPLAY INVISIBLE (-6200 1725);
FORCEPROP 1 LAST PATH I367
J 0
(-6527 1850);
DISPLAY 0.872340 (-6527 1850);
PAINT GREEN (-6527 1850);
DISPLAY INVISIBLE (-6527 1850);
FORCEADD TAP..6
(-6675 2000);
FORCEPROP 3 LASTPIN (-6625 2000) SIG_NAME GMI_CPU1_G3_CPU0_G1_TX_DN<9>
J 0
(-6615 2010);
DISPLAY 0.659574 (-6615 2010);
PAINT MONO (-6615 2010);
DISPLAY INVISIBLE (-6615 2010);
FORCEPROP 1 LASTPIN (-6625 2000) BN 9
J 0
(-6677 2008);
DISPLAY 0.489362 (-6677 2008);
PAINT MONO (-6677 2008);
FORCEPROP 2 LAST CDS_LIB standard
J 0
(-6675 2000);
DISPLAY INVISIBLE (-6675 2000);
FORCEPROP 1 LAST BODY_TYPE PLUMBING
J 0
(-6675 1950);
DISPLAY 0.574468 (-6675 1950);
PAINT GREEN (-6675 1950);
DISPLAY INVISIBLE (-6675 1950);
FORCEPROP 1 LAST HDL_TAP TRUE
J 0
(-6350 1875);
DISPLAY 0.574468 (-6350 1875);
PAINT GREEN (-6350 1875);
DISPLAY INVISIBLE (-6350 1875);
FORCEPROP 1 LAST PATH I368
J 0
(-6677 2000);
DISPLAY 0.872340 (-6677 2000);
PAINT GREEN (-6677 2000);
DISPLAY INVISIBLE (-6677 2000);
FORCEADD TAP..6
(-6675 1900);
FORCEPROP 3 LASTPIN (-6625 1900) SIG_NAME GMI_CPU1_G3_CPU0_G1_TX_DN<10>
J 0
(-6615 1910);
DISPLAY 0.659574 (-6615 1910);
PAINT MONO (-6615 1910);
DISPLAY INVISIBLE (-6615 1910);
FORCEPROP 1 LASTPIN (-6625 1900) BN 10
J 0
(-6677 1908);
DISPLAY 0.489362 (-6677 1908);
PAINT MONO (-6677 1908);
FORCEPROP 2 LAST CDS_LIB standard
J 0
(-6675 1900);
DISPLAY INVISIBLE (-6675 1900);
FORCEPROP 1 LAST BODY_TYPE PLUMBING
J 0
(-6675 1850);
DISPLAY 0.574468 (-6675 1850);
PAINT GREEN (-6675 1850);
DISPLAY INVISIBLE (-6675 1850);
FORCEPROP 1 LAST HDL_TAP TRUE
J 0
(-6350 1775);
DISPLAY 0.574468 (-6350 1775);
PAINT GREEN (-6350 1775);
DISPLAY INVISIBLE (-6350 1775);
FORCEPROP 1 LAST PATH I369
J 0
(-6677 1900);
DISPLAY 0.872340 (-6677 1900);
PAINT GREEN (-6677 1900);
DISPLAY INVISIBLE (-6677 1900);
FORCEADD TAP..6
(-6675 1800);
FORCEPROP 3 LASTPIN (-6625 1800) SIG_NAME GMI_CPU1_G3_CPU0_G1_TX_DN<11>
J 0
(-6615 1810);
DISPLAY 0.659574 (-6615 1810);
PAINT MONO (-6615 1810);
DISPLAY INVISIBLE (-6615 1810);
FORCEPROP 1 LASTPIN (-6625 1800) BN 11
J 0
(-6677 1808);
DISPLAY 0.489362 (-6677 1808);
PAINT MONO (-6677 1808);
FORCEPROP 2 LAST CDS_LIB standard
J 0
(-6675 1800);
DISPLAY INVISIBLE (-6675 1800);
FORCEPROP 1 LAST BODY_TYPE PLUMBING
J 0
(-6675 1750);
DISPLAY 0.574468 (-6675 1750);
PAINT GREEN (-6675 1750);
DISPLAY INVISIBLE (-6675 1750);
FORCEPROP 1 LAST HDL_TAP TRUE
J 0
(-6350 1675);
DISPLAY 0.574468 (-6350 1675);
PAINT GREEN (-6350 1675);
DISPLAY INVISIBLE (-6350 1675);
FORCEPROP 1 LAST PATH I370
J 0
(-6677 1800);
DISPLAY 0.872340 (-6677 1800);
PAINT GREEN (-6677 1800);
DISPLAY INVISIBLE (-6677 1800);
FORCEADD TAP..6
(-6525 1750);
FORCEPROP 3 LASTPIN (-6475 1750) SIG_NAME GMI_CPU1_G3_CPU0_G1_TX_DP<12>
J 0
(-6465 1760);
DISPLAY 0.659574 (-6465 1760);
PAINT MONO (-6465 1760);
DISPLAY INVISIBLE (-6465 1760);
FORCEPROP 1 LASTPIN (-6475 1750) BN 12
J 0
(-6527 1758);
DISPLAY 0.489362 (-6527 1758);
PAINT MONO (-6527 1758);
FORCEPROP 2 LAST CDS_LIB standard
J 0
(-6525 1750);
DISPLAY INVISIBLE (-6525 1750);
FORCEPROP 1 LAST BODY_TYPE PLUMBING
J 0
(-6525 1700);
DISPLAY 0.574468 (-6525 1700);
PAINT GREEN (-6525 1700);
DISPLAY INVISIBLE (-6525 1700);
FORCEPROP 1 LAST HDL_TAP TRUE
J 0
(-6200 1625);
DISPLAY 0.574468 (-6200 1625);
PAINT GREEN (-6200 1625);
DISPLAY INVISIBLE (-6200 1625);
FORCEPROP 1 LAST PATH I371
J 0
(-6527 1750);
DISPLAY 0.872340 (-6527 1750);
PAINT GREEN (-6527 1750);
DISPLAY INVISIBLE (-6527 1750);
FORCEADD TAP..6
(-6525 1650);
FORCEPROP 3 LASTPIN (-6475 1650) SIG_NAME GMI_CPU1_G3_CPU0_G1_TX_DP<13>
J 0
(-6465 1660);
DISPLAY 0.659574 (-6465 1660);
PAINT MONO (-6465 1660);
DISPLAY INVISIBLE (-6465 1660);
FORCEPROP 1 LASTPIN (-6475 1650) BN 13
J 0
(-6527 1658);
DISPLAY 0.489362 (-6527 1658);
PAINT MONO (-6527 1658);
FORCEPROP 2 LAST CDS_LIB standard
J 0
(-6525 1650);
DISPLAY INVISIBLE (-6525 1650);
FORCEPROP 1 LAST BODY_TYPE PLUMBING
J 0
(-6525 1600);
DISPLAY 0.574468 (-6525 1600);
PAINT GREEN (-6525 1600);
DISPLAY INVISIBLE (-6525 1600);
FORCEPROP 1 LAST HDL_TAP TRUE
J 0
(-6200 1525);
DISPLAY 0.574468 (-6200 1525);
PAINT GREEN (-6200 1525);
DISPLAY INVISIBLE (-6200 1525);
FORCEPROP 1 LAST PATH I372
J 0
(-6527 1650);
DISPLAY 0.872340 (-6527 1650);
PAINT GREEN (-6527 1650);
DISPLAY INVISIBLE (-6527 1650);
FORCEADD TAP..6
(-6525 1550);
FORCEPROP 3 LASTPIN (-6475 1550) SIG_NAME GMI_CPU1_G3_CPU0_G1_TX_DP<14>
J 0
(-6465 1560);
DISPLAY 0.659574 (-6465 1560);
PAINT MONO (-6465 1560);
DISPLAY INVISIBLE (-6465 1560);
FORCEPROP 1 LASTPIN (-6475 1550) BN 14
J 0
(-6527 1558);
DISPLAY 0.489362 (-6527 1558);
PAINT MONO (-6527 1558);
FORCEPROP 2 LAST CDS_LIB standard
J 0
(-6525 1550);
DISPLAY INVISIBLE (-6525 1550);
FORCEPROP 1 LAST BODY_TYPE PLUMBING
J 0
(-6525 1500);
DISPLAY 0.574468 (-6525 1500);
PAINT GREEN (-6525 1500);
DISPLAY INVISIBLE (-6525 1500);
FORCEPROP 1 LAST HDL_TAP TRUE
J 0
(-6200 1425);
DISPLAY 0.574468 (-6200 1425);
PAINT GREEN (-6200 1425);
DISPLAY INVISIBLE (-6200 1425);
FORCEPROP 1 LAST PATH I373
J 0
(-6527 1550);
DISPLAY 0.872340 (-6527 1550);
PAINT GREEN (-6527 1550);
DISPLAY INVISIBLE (-6527 1550);
FORCEADD TAP..6
(-6675 1700);
FORCEPROP 3 LASTPIN (-6625 1700) SIG_NAME GMI_CPU1_G3_CPU0_G1_TX_DN<12>
J 0
(-6615 1710);
DISPLAY 0.659574 (-6615 1710);
PAINT MONO (-6615 1710);
DISPLAY INVISIBLE (-6615 1710);
FORCEPROP 1 LASTPIN (-6625 1700) BN 12
J 0
(-6677 1708);
DISPLAY 0.489362 (-6677 1708);
PAINT MONO (-6677 1708);
FORCEPROP 2 LAST CDS_LIB standard
J 0
(-6675 1700);
DISPLAY INVISIBLE (-6675 1700);
FORCEPROP 1 LAST BODY_TYPE PLUMBING
J 0
(-6675 1650);
DISPLAY 0.574468 (-6675 1650);
PAINT GREEN (-6675 1650);
DISPLAY INVISIBLE (-6675 1650);
FORCEPROP 1 LAST HDL_TAP TRUE
J 0
(-6350 1575);
DISPLAY 0.574468 (-6350 1575);
PAINT GREEN (-6350 1575);
DISPLAY INVISIBLE (-6350 1575);
FORCEPROP 1 LAST PATH I374
J 0
(-6677 1700);
DISPLAY 0.872340 (-6677 1700);
PAINT GREEN (-6677 1700);
DISPLAY INVISIBLE (-6677 1700);
FORCEADD TAP..6
(-6675 1600);
FORCEPROP 3 LASTPIN (-6625 1600) SIG_NAME GMI_CPU1_G3_CPU0_G1_TX_DN<13>
J 0
(-6615 1610);
DISPLAY 0.659574 (-6615 1610);
PAINT MONO (-6615 1610);
DISPLAY INVISIBLE (-6615 1610);
FORCEPROP 1 LASTPIN (-6625 1600) BN 13
J 0
(-6677 1608);
DISPLAY 0.489362 (-6677 1608);
PAINT MONO (-6677 1608);
FORCEPROP 2 LAST CDS_LIB standard
J 0
(-6675 1600);
DISPLAY INVISIBLE (-6675 1600);
FORCEPROP 1 LAST BODY_TYPE PLUMBING
J 0
(-6675 1550);
DISPLAY 0.574468 (-6675 1550);
PAINT GREEN (-6675 1550);
DISPLAY INVISIBLE (-6675 1550);
FORCEPROP 1 LAST HDL_TAP TRUE
J 0
(-6350 1475);
DISPLAY 0.574468 (-6350 1475);
PAINT GREEN (-6350 1475);
DISPLAY INVISIBLE (-6350 1475);
FORCEPROP 1 LAST PATH I375
J 0
(-6677 1600);
DISPLAY 0.872340 (-6677 1600);
PAINT GREEN (-6677 1600);
DISPLAY INVISIBLE (-6677 1600);
FORCEADD TAP..6
(-6525 1450);
FORCEPROP 3 LASTPIN (-6475 1450) SIG_NAME GMI_CPU1_G3_CPU0_G1_TX_DP<15>
J 0
(-6465 1460);
DISPLAY 0.659574 (-6465 1460);
PAINT MONO (-6465 1460);
DISPLAY INVISIBLE (-6465 1460);
FORCEPROP 1 LASTPIN (-6475 1450) BN 15
J 0
(-6527 1458);
DISPLAY 0.489362 (-6527 1458);
PAINT MONO (-6527 1458);
FORCEPROP 2 LAST CDS_LIB standard
J 0
(-6525 1450);
DISPLAY INVISIBLE (-6525 1450);
FORCEPROP 1 LAST BODY_TYPE PLUMBING
J 0
(-6525 1400);
DISPLAY 0.574468 (-6525 1400);
PAINT GREEN (-6525 1400);
DISPLAY INVISIBLE (-6525 1400);
FORCEPROP 1 LAST HDL_TAP TRUE
J 0
(-6200 1325);
DISPLAY 0.574468 (-6200 1325);
PAINT GREEN (-6200 1325);
DISPLAY INVISIBLE (-6200 1325);
FORCEPROP 1 LAST PATH I376
J 0
(-6527 1450);
DISPLAY 0.872340 (-6527 1450);
PAINT GREEN (-6527 1450);
DISPLAY INVISIBLE (-6527 1450);
FORCEADD TAP..6
(-6675 1400);
FORCEPROP 3 LASTPIN (-6625 1400) SIG_NAME GMI_CPU1_G3_CPU0_G1_TX_DN<15>
J 0
(-6615 1410);
DISPLAY 0.659574 (-6615 1410);
PAINT MONO (-6615 1410);
DISPLAY INVISIBLE (-6615 1410);
FORCEPROP 1 LASTPIN (-6625 1400) BN 15
J 0
(-6677 1408);
DISPLAY 0.489362 (-6677 1408);
PAINT MONO (-6677 1408);
FORCEPROP 2 LAST CDS_LIB standard
J 0
(-6675 1400);
DISPLAY INVISIBLE (-6675 1400);
FORCEPROP 1 LAST BODY_TYPE PLUMBING
J 0
(-6675 1350);
DISPLAY 0.574468 (-6675 1350);
PAINT GREEN (-6675 1350);
DISPLAY INVISIBLE (-6675 1350);
FORCEPROP 1 LAST HDL_TAP TRUE
J 0
(-6350 1275);
DISPLAY 0.574468 (-6350 1275);
PAINT GREEN (-6350 1275);
DISPLAY INVISIBLE (-6350 1275);
FORCEPROP 1 LAST PATH I377
J 0
(-6677 1400);
DISPLAY 0.872340 (-6677 1400);
PAINT GREEN (-6677 1400);
DISPLAY INVISIBLE (-6677 1400);
FORCEADD TAP..6
(-6675 1500);
FORCEPROP 3 LASTPIN (-6625 1500) SIG_NAME GMI_CPU1_G3_CPU0_G1_TX_DN<14>
J 0
(-6615 1510);
DISPLAY 0.659574 (-6615 1510);
PAINT MONO (-6615 1510);
DISPLAY INVISIBLE (-6615 1510);
FORCEPROP 1 LASTPIN (-6625 1500) BN 14
J 0
(-6677 1508);
DISPLAY 0.489362 (-6677 1508);
PAINT MONO (-6677 1508);
FORCEPROP 2 LAST CDS_LIB standard
J 0
(-6675 1500);
DISPLAY INVISIBLE (-6675 1500);
FORCEPROP 1 LAST BODY_TYPE PLUMBING
J 0
(-6675 1450);
DISPLAY 0.574468 (-6675 1450);
PAINT GREEN (-6675 1450);
DISPLAY INVISIBLE (-6675 1450);
FORCEPROP 1 LAST HDL_TAP TRUE
J 0
(-6350 1375);
DISPLAY 0.574468 (-6350 1375);
PAINT GREEN (-6350 1375);
DISPLAY INVISIBLE (-6350 1375);
FORCEPROP 1 LAST PATH I378
J 0
(-6677 1500);
DISPLAY 0.872340 (-6677 1500);
PAINT GREEN (-6677 1500);
DISPLAY INVISIBLE (-6677 1500);
FORCEADD QUANTA_TITLE_BLOCK_C..1
(-100 100);
FORCEPROP 0 LAST CDS_CON_LAST_MODIFIED Thu Sep 14 16:11:51 2023
J 0
(-1985 115);
DISPLAY INVISIBLE (-1985 115);
FORCEPROP 1 LAST CUSTOM_TXT_CDS <CON_LAST_MODIFIED>
J 0
(-1985 115);
DISPLAY 0.978723 (-1985 115);
FORCEPROP 2 LAST CUSTOM_TXT_CDS <XR_PAGE_TITLE>
J 0
(-7990 5350);
DISPLAY 0.638298 (-7990 5350);
PAINT PINK (-7990 5350);
DISPLAY INVISIBLE (-7990 5350);
FORCEPROP 1 LAST CUSTOM_TXT_CDS <NAME_2>
J 0
(-3275 150);
FORCEPROP 1 LAST CUSTOM_TXT_CDS <NAME_1>
J 0
(-3275 275);
FORCEPROP 1 LAST CUSTOM_TXT_CDS <Q_NUMBER>
J 0
(-1503 203);
DISPLAY 1.212766 (-1503 203);
FORCEPROP 1 LAST CUSTOM_TXT_CDS <Q_PROJ>
J 0
(-2482 202);
DISPLAY 1.212766 (-2482 202);
FORCEPROP 1 LAST CUSTOM_TXT_CDS <Q_REV>
J 0
(-284 203);
DISPLAY 1.212766 (-284 203);
FORCEPROP 1 LAST CUSTOM_TXT_CDS <CON_PAGE_NUM> OF <CON_TOTAL_PAGES>
J 0
(-546 118);
DISPLAY 0.978723 (-546 118);
FORCEPROP 1 LAST Q_TITLE CPU0 PCIE G0/G1
J 0
(-9375 150);
DISPLAY 2.446809 (-9375 150);
PAINT GREEN (-9375 150);
FORCEPROP 2 LAST PAGE_BORDER TRUE
J 0
(-7990 5350);
DISPLAY 0.638298 (-7990 5350);
PAINT PINK (-7990 5350);
DISPLAY INVISIBLE (-7990 5350);
FORCEPROP 1 LAST CDS_LMAN_SYM_OUTLINE -9475,6775,100,-125
J 0
(-100 100);
DISPLAY 0.468085 (-100 100);
PAINT GREEN (-100 100);
DISPLAY INVISIBLE (-100 100);
FORCEPROP 2 LAST CDS_LIB pure_quanta
J 0
(-100 100);
DISPLAY INVISIBLE (-100 100);
FORCEPROP 2 LAST CDS_XR_PAGE_TITLE CR-22 : @T6G_MB_LIB.T6G(SCH_1):PAGE22
J 0
(-7990 5350);
DISPLAY 0.638298 (-7990 5350);
PAINT PINK (-7990 5350);
DISPLAY INVISIBLE (-7990 5350);
FORCEPROP 1 LAST Q_DEPT BU9
J 1
(-3863 149);
DISPLAY 1.957447 (-3863 149);
PAINT GREEN (-3863 149);
DISPLAY INVISIBLE (-3863 149);
FORCEPROP 1 LAST COMMENT_BODY TRUE
J 0
(-88 87);
DISPLAY 0.978723 (-88 87);
PAINT GREEN (-88 87);
DISPLAY INVISIBLE (-88 87);
WIRE 17 -1 (-2900 5850)(-2900 5650);
WIRE 17 -1 (-2900 5850)(-1875 5850);
FORCEPROP 2 LAST SIG_NAME GMI_CPU0_G0_CPU1_G2_TX_DN<15:0>
J 0
(-2860 5860);
DISPLAY 0.489362 (-2860 5860);
WIRE 17 -1 (-2900 5650)(-2900 5550);
WIRE 17 -1 (-2900 5550)(-2900 5450);
WIRE 17 -1 (-2900 5450)(-2900 5350);
WIRE 17 -1 (-2900 5350)(-2900 5250);
WIRE 17 -1 (-2900 5250)(-2900 5150);
WIRE 17 -1 (-2900 5150)(-2900 5050);
WIRE 17 -1 (-2900 5050)(-2900 4950);
WIRE 17 -1 (-2900 4950)(-2900 4850);
WIRE 17 -1 (-2900 4850)(-2900 4750);
WIRE 17 -1 (-2900 4750)(-2900 4650);
WIRE 17 -1 (-2900 4650)(-2900 4550);
WIRE 17 -1 (-2900 4550)(-2900 4450);
WIRE 17 -1 (-2900 4450)(-2900 4350);
WIRE 17 -1 (-2900 4350)(-2900 4250);
WIRE 17 -1 (-2900 4250)(-2900 4150);
WIRE 17 -1 (-3050 5900)(-3050 5700);
WIRE 17 -1 (-3050 5900)(-1875 5900);
FORCEPROP 2 LAST SIG_NAME GMI_CPU0_G0_CPU1_G2_TX_DP<15:0>
J 0
(-2860 5910);
DISPLAY 0.489362 (-2860 5910);
WIRE 17 -1 (-3050 5700)(-3050 5600);
WIRE 17 -1 (-3050 5600)(-3050 5500);
WIRE 17 -1 (-3050 5500)(-3050 5400);
WIRE 17 -1 (-3050 5400)(-3050 5300);
WIRE 17 -1 (-3050 5300)(-3050 5200);
WIRE 17 -1 (-3050 5200)(-3050 5100);
WIRE 17 -1 (-3050 5100)(-3050 5000);
WIRE 17 -1 (-3050 5000)(-3050 4900);
WIRE 17 -1 (-3050 4900)(-3050 4800);
WIRE 17 -1 (-3050 4800)(-3050 4700);
WIRE 17 -1 (-3050 4700)(-3050 4600);
WIRE 17 -1 (-3050 4600)(-3050 4500);
WIRE 17 -1 (-3050 4500)(-3050 4400);
WIRE 17 -1 (-3050 4400)(-3050 4300);
WIRE 17 -1 (-3050 4300)(-3050 4200);
WIRE 17 -1 (-2900 2225)(-2900 2125);
WIRE 17 -1 (-2900 2325)(-2900 2225);
WIRE 17 -1 (-2900 2125)(-2900 2025);
WIRE 17 -1 (-2900 2025)(-2900 1925);
WIRE 17 -1 (-2900 2425)(-2900 2325);
WIRE 17 -1 (-2900 2525)(-2900 2425);
WIRE 17 -1 (-2900 1925)(-2900 1825);
WIRE 17 -1 (-2900 1825)(-2900 1725);
WIRE 17 -1 (-2900 2625)(-2900 2525);
WIRE 17 -1 (-2900 2725)(-2900 2625);
WIRE 17 -1 (-2900 1725)(-2900 1625);
WIRE 17 -1 (-2900 1625)(-2900 1525);
WIRE 17 -1 (-2900 2825)(-2900 2725);
WIRE 17 -1 (-2900 2925)(-2900 2825);
WIRE 17 -1 (-2900 1525)(-2900 1425);
WIRE 17 -1 (-2900 3125)(-2900 2925);
FORCEPROP 2 LAST SIG_NAME GMI_CPU0_G1_CPU1_G3_TX_DN<15:0>
J 0
(-2935 3135);
DISPLAY 0.489362 (-2935 3135);
WIRE 17 -1 (-3050 3175)(-3050 2975);
WIRE 17 -1 (-3050 3175)(-2025 3175);
FORCEPROP 2 LAST SIG_NAME GMI_CPU0_G1_CPU1_G3_TX_DP<15:0>
J 0
(-2935 3185);
DISPLAY 0.489362 (-2935 3185);
WIRE 17 -1 (-3050 2975)(-3050 2875);
WIRE 17 -1 (-3050 2875)(-3050 2775);
WIRE 17 -1 (-3050 2775)(-3050 2675);
WIRE 17 -1 (-3050 2675)(-3050 2575);
WIRE 17 -1 (-3050 2575)(-3050 2475);
WIRE 17 -1 (-3050 2475)(-3050 2375);
WIRE 17 -1 (-3050 2375)(-3050 2275);
WIRE 17 -1 (-3050 2175)(-3050 2075);
WIRE 17 -1 (-3050 2275)(-3050 2175);
WIRE 17 -1 (-3050 2075)(-3050 1975);
WIRE 17 -1 (-3050 1975)(-3050 1875);
WIRE 17 -1 (-3050 1875)(-3050 1775);
WIRE 17 -1 (-3050 1775)(-3050 1675);
WIRE 17 -1 (-3050 1675)(-3050 1575);
WIRE 17 -1 (-3050 1575)(-3050 1475);
WIRE 17 -1 (-6725 5550)(-6725 5650);
WIRE 17 -1 (-6725 5450)(-6725 5550);
WIRE 17 -1 (-6725 5650)(-6725 5850);
WIRE 17 -1 (-6725 5850)(-7725 5850);
FORCEPROP 2 LAST SIG_NAME GMI_CPU1_G2_CPU0_G0_TX_DN<15:0>
J 0
(-7685 5860);
DISPLAY 0.489362 (-7685 5860);
WIRE 17 -1 (-6725 5350)(-6725 5450);
WIRE 17 -1 (-6725 5250)(-6725 5350);
WIRE 17 -1 (-6725 5150)(-6725 5250);
WIRE 17 -1 (-6725 5050)(-6725 5150);
WIRE 17 -1 (-6725 4950)(-6725 5050);
WIRE 17 -1 (-6725 4850)(-6725 4950);
WIRE 17 -1 (-6725 4750)(-6725 4850);
WIRE 17 -1 (-6725 4650)(-6725 4750);
WIRE 17 -1 (-6725 4550)(-6725 4650);
WIRE 17 -1 (-6725 4450)(-6725 4550);
WIRE 17 -1 (-6725 4350)(-6725 4450);
WIRE 17 -1 (-6725 4250)(-6725 4350);
WIRE 17 -1 (-6725 4150)(-6725 4250);
WIRE 17 -1 (-6575 5600)(-6575 5700);
WIRE 17 -1 (-6575 5500)(-6575 5600);
WIRE 17 -1 (-6575 5700)(-6575 5900);
WIRE 17 -1 (-6575 5900)(-7725 5900);
FORCEPROP 2 LAST SIG_NAME GMI_CPU1_G2_CPU0_G0_TX_DP<15:0>
J 0
(-7685 5910);
DISPLAY 0.489362 (-7685 5910);
WIRE 17 -1 (-6575 5400)(-6575 5500);
WIRE 17 -1 (-6575 5300)(-6575 5400);
WIRE 17 -1 (-6575 5200)(-6575 5300);
WIRE 17 -1 (-6575 5100)(-6575 5200);
WIRE 17 -1 (-6575 5000)(-6575 5100);
WIRE 17 -1 (-6575 4900)(-6575 5000);
WIRE 17 -1 (-6575 4800)(-6575 4900);
WIRE 17 -1 (-6575 4700)(-6575 4800);
WIRE 17 -1 (-6575 4600)(-6575 4700);
WIRE 17 -1 (-6575 4500)(-6575 4600);
WIRE 17 -1 (-6575 4400)(-6575 4500);
WIRE 17 -1 (-6575 4300)(-6575 4400);
WIRE 17 -1 (-6575 4200)(-6575 4300);
WIRE 17 -1 (-6575 1475)(-6575 1575);
WIRE 17 -1 (-6575 1575)(-6575 1675);
WIRE 17 -1 (-6575 1675)(-6575 1775);
WIRE 17 -1 (-6575 1775)(-6575 1875);
WIRE 17 -1 (-6575 1875)(-6575 1975);
WIRE 17 -1 (-6575 1975)(-6575 2075);
WIRE 17 -1 (-6575 2075)(-6575 2175);
WIRE 17 -1 (-6575 2175)(-6575 2275);
WIRE 17 -1 (-6575 2275)(-6575 2375);
WIRE 17 -1 (-6575 2375)(-6575 2475);
WIRE 17 -1 (-6575 2475)(-6575 2575);
WIRE 17 -1 (-6575 2575)(-6575 2675);
WIRE 17 -1 (-6575 2675)(-6575 2775);
WIRE 17 -1 (-6575 2775)(-6575 2875);
WIRE 17 -1 (-6575 2875)(-6575 2975);
WIRE 17 -1 (-6575 2975)(-6575 3175);
WIRE 17 -1 (-6575 3175)(-7575 3175);
FORCEPROP 2 LAST SIG_NAME GMI_CPU1_G3_CPU0_G1_TX_DP<15:0>
J 0
(-7585 3185);
DISPLAY 0.489362 (-7585 3185);
WIRE 17 -1 (-6725 1425)(-6725 1525);
WIRE 17 -1 (-6725 1525)(-6725 1625);
WIRE 17 -1 (-6725 1625)(-6725 1725);
WIRE 17 -1 (-6725 1725)(-6725 1825);
WIRE 17 -1 (-6725 1825)(-6725 1925);
WIRE 17 -1 (-6725 1925)(-6725 2025);
WIRE 17 -1 (-6725 2025)(-6725 2125);
WIRE 17 -1 (-6725 2125)(-6725 2225);
WIRE 17 -1 (-6725 2225)(-6725 2325);
WIRE 17 -1 (-6725 2325)(-6725 2425);
WIRE 17 -1 (-6725 2425)(-6725 2525);
WIRE 17 -1 (-6725 2525)(-6725 2625);
WIRE 17 -1 (-6725 2625)(-6725 2725);
WIRE 17 -1 (-6725 2725)(-6725 2825);
WIRE 17 -1 (-6725 2825)(-6725 2925);
WIRE 17 -1 (-6725 2925)(-6725 3125);
WIRE 17 -1 (-6725 3125)(-7575 3125);
WIRE 17 -1 (-2900 3125)(-2025 3125);
WIRE 16 -1 (-6475 4975)(-6025 4975);
WIRE 16 -1 (-6625 2200)(-6025 2200);
WIRE 16 -1 (-6625 2300)(-6025 2300);
WIRE 16 -1 (-6625 2400)(-6025 2400);
WIRE 16 -1 (-6475 2250)(-6025 2250);
WIRE 16 -1 (-6625 2500)(-6025 2500);
WIRE 16 -1 (-6475 2350)(-6025 2350);
WIRE 16 -1 (-6625 2600)(-6025 2600);
WIRE 16 -1 (-6475 2450)(-6025 2450);
WIRE 16 -1 (-6625 2700)(-6025 2700);
WIRE 16 -1 (-6475 2550)(-6025 2550);
WIRE 16 -1 (-6625 2800)(-6025 2800);
WIRE 16 -1 (-6475 2650)(-6025 2650);
WIRE 16 -1 (-6625 2900)(-6025 2900);
WIRE 16 -1 (-6475 2750)(-6025 2750);
WIRE 16 -1 (-6475 2850)(-6025 2850);
WIRE 16 -1 (-6475 2950)(-6025 2950);
WIRE 16 -1 (-6625 2100)(-6025 2100);
WIRE 16 -1 (-6625 2000)(-6025 2000);
WIRE 16 -1 (-6625 1900)(-6025 1900);
WIRE 16 -1 (-6625 1800)(-6025 1800);
WIRE 16 -1 (-6625 1700)(-6025 1700);
WIRE 16 -1 (-6625 1600)(-6025 1600);
WIRE 16 -1 (-6625 1500)(-6025 1500);
WIRE 16 -1 (-6625 1400)(-6025 1400);
WIRE 16 -1 (-6475 2150)(-6025 2150);
WIRE 16 -1 (-6475 2050)(-6025 2050);
WIRE 16 -1 (-6475 1950)(-6025 1950);
WIRE 16 -1 (-6475 1850)(-6025 1850);
WIRE 16 -1 (-6475 1750)(-6025 1750);
WIRE 16 -1 (-6475 1650)(-6025 1650);
WIRE 16 -1 (-6475 1550)(-6025 1550);
WIRE 16 -1 (-6475 1450)(-6025 1450);
WIRE 16 -1 (-6475 4175)(-6025 4175);
WIRE 16 -1 (-6475 4275)(-6025 4275);
WIRE 16 -1 (-6475 4375)(-6025 4375);
WIRE 16 -1 (-6475 4475)(-6025 4475);
WIRE 16 -1 (-6475 4575)(-6025 4575);
WIRE 16 -1 (-6475 4675)(-6025 4675);
WIRE 16 -1 (-6475 4775)(-6025 4775);
WIRE 16 -1 (-6475 4875)(-6025 4875);
WIRE 16 -1 (-6475 5075)(-6025 5075);
WIRE 16 -1 (-6475 5175)(-6025 5175);
WIRE 16 -1 (-6475 5275)(-6025 5275);
WIRE 16 -1 (-6475 5375)(-6025 5375);
WIRE 16 -1 (-6475 5475)(-6025 5475);
WIRE 16 -1 (-6475 5575)(-6025 5575);
WIRE 16 -1 (-6475 5675)(-6025 5675);
WIRE 16 -1 (-6625 4125)(-6025 4125);
WIRE 16 -1 (-6625 4225)(-6025 4225);
WIRE 16 -1 (-6625 4325)(-6025 4325);
WIRE 16 -1 (-6625 4425)(-6025 4425);
WIRE 16 -1 (-6625 4525)(-6025 4525);
WIRE 16 -1 (-6625 4625)(-6025 4625);
WIRE 16 -1 (-6625 4725)(-6025 4725);
WIRE 16 -1 (-6625 4825)(-6025 4825);
WIRE 16 -1 (-6625 4925)(-6025 4925);
WIRE 16 -1 (-6625 5025)(-6025 5025);
WIRE 16 -1 (-6625 5125)(-6025 5125);
WIRE 16 -1 (-6625 5225)(-6025 5225);
WIRE 16 -1 (-6625 5325)(-6025 5325);
WIRE 16 -1 (-6625 5425)(-6025 5425);
WIRE 16 -1 (-6625 5525)(-6025 5525);
WIRE 16 -1 (-6625 5625)(-6025 5625);
WIRE 16 -1 (-3150 1450)(-3525 1450);
WIRE 16 -1 (-3525 1950)(-3150 1950);
WIRE 16 -1 (-3525 1850)(-3150 1850);
WIRE 16 -1 (-3525 1750)(-3150 1750);
WIRE 16 -1 (-3525 1650)(-3150 1650);
WIRE 16 -1 (-3525 1550)(-3150 1550);
WIRE 16 -1 (-3525 2000)(-3000 2000);
WIRE 16 -1 (-3525 1900)(-3000 1900);
WIRE 16 -1 (-3525 1800)(-3000 1800);
WIRE 16 -1 (-3525 1700)(-3000 1700);
WIRE 16 -1 (-3525 1600)(-3000 1600);
WIRE 16 -1 (-3525 1500)(-3000 1500);
WIRE 16 -1 (-3000 1400)(-3525 1400);
WIRE 16 -1 (-3525 2250)(-3150 2250);
WIRE 16 -1 (-3525 2350)(-3150 2350);
WIRE 16 -1 (-3525 2450)(-3150 2450);
WIRE 16 -1 (-3525 2550)(-3150 2550);
WIRE 16 -1 (-3525 2150)(-3150 2150);
WIRE 16 -1 (-3525 2050)(-3150 2050);
WIRE 16 -1 (-3525 2650)(-3150 2650);
WIRE 16 -1 (-3525 2750)(-3150 2750);
WIRE 16 -1 (-3525 2850)(-3150 2850);
WIRE 16 -1 (-3525 2950)(-3150 2950);
WIRE 16 -1 (-3525 2200)(-3000 2200);
WIRE 16 -1 (-3525 2300)(-3000 2300);
WIRE 16 -1 (-3525 2400)(-3000 2400);
WIRE 16 -1 (-3525 2500)(-3000 2500);
WIRE 16 -1 (-3525 2600)(-3000 2600);
WIRE 16 -1 (-3525 2700)(-3000 2700);
WIRE 16 -1 (-3525 2800)(-3000 2800);
WIRE 16 -1 (-3525 2900)(-3000 2900);
WIRE 16 -1 (-3525 2100)(-3000 2100);
WIRE 16 -1 (-3525 4175)(-3150 4175);
WIRE 16 -1 (-3525 4275)(-3150 4275);
WIRE 16 -1 (-3525 4375)(-3150 4375);
WIRE 16 -1 (-3525 4475)(-3150 4475);
WIRE 16 -1 (-3525 4575)(-3150 4575);
WIRE 16 -1 (-3525 4675)(-3150 4675);
WIRE 16 -1 (-3525 4775)(-3150 4775);
WIRE 16 -1 (-3525 4875)(-3150 4875);
WIRE 16 -1 (-3525 4975)(-3150 4975);
WIRE 16 -1 (-3525 5075)(-3150 5075);
WIRE 16 -1 (-3525 5175)(-3150 5175);
WIRE 16 -1 (-3525 5275)(-3150 5275);
WIRE 16 -1 (-3525 5375)(-3150 5375);
WIRE 16 -1 (-3525 5475)(-3150 5475);
WIRE 16 -1 (-3525 5575)(-3150 5575);
WIRE 16 -1 (-3525 5675)(-3150 5675);
WIRE 16 -1 (-3525 4125)(-3000 4125);
WIRE 16 -1 (-3525 4225)(-3000 4225);
WIRE 16 -1 (-3525 4325)(-3000 4325);
WIRE 16 -1 (-3525 4425)(-3000 4425);
WIRE 16 -1 (-3525 4525)(-3000 4525);
WIRE 16 -1 (-3525 4625)(-3000 4625);
WIRE 16 -1 (-3525 4725)(-3000 4725);
WIRE 16 -1 (-3525 4825)(-3000 4825);
WIRE 16 -1 (-3525 4925)(-3000 4925);
WIRE 16 -1 (-3525 5025)(-3000 5025);
WIRE 16 -1 (-3525 5125)(-3000 5125);
WIRE 16 -1 (-3525 5225)(-3000 5225);
WIRE 16 -1 (-3525 5325)(-3000 5325);
WIRE 16 -1 (-3525 5425)(-3000 5425);
WIRE 16 -1 (-3525 5525)(-3000 5525);
WIRE 16 -1 (-3525 5625)(-3000 5625);
QUIT
